(kicad_sch
	(version 20250114)
	(generator "eeschema")
	(generator_version "9.0")
	(paper "A3")
	(title_block
		(title "SDI-MIPI Video Converter")
		(date "2023-10-12")
		(rev "1.1.4")
		(comment 1 "www.antmicro.com")
		(comment 2 "Antmicro Ltd.")
	)
	(text "DONE"
		(exclude_from_sim no)
		(at 298.45 195.58 0)
		(effects
			(font
				(size 3 3)
			)
			(justify left bottom)
		)
	)
	(text "FPGA"
		(exclude_from_sim no)
		(at 90.17 22.86 0)
		(effects
			(font
				(size 6 6)
			)
			(justify left bottom)
		)
	)
	(text "OSCILLATOR"
		(exclude_from_sim no)
		(at 130.81 229.87 0)
		(effects
			(font
				(size 6 6)
			)
			(justify left bottom)
		)
	)
	(text "OPTIONAL, NORMALLY DNP"
		(exclude_from_sim no)
		(at 138.43 233.68 0)
		(effects
			(font
				(size 2 2)
			)
			(justify left bottom)
		)
	)
	(text "FPGA CONFIGURATION"
		(exclude_from_sim no)
		(at 247.65 24.13 0)
		(effects
			(font
				(size 6 6)
			)
			(justify left bottom)
		)
	)
	(text "JTAG CONNECTOR"
		(exclude_from_sim no)
		(at 346.075 92.075 0)
		(effects
			(font
				(size 3 3)
			)
			(justify left bottom)
		)
	)
	(text "CONFIGURATION FLASH"
		(exclude_from_sim no)
		(at 308.61 33.02 0)
		(effects
			(font
				(size 3 3)
			)
			(justify left bottom)
		)
	)
	(text "I2C TO SPI BRIDGE"
		(exclude_from_sim no)
		(at 246.38 113.03 0)
		(effects
			(font
				(size 3 3)
			)
			(justify left bottom)
		)
	)
	(text "INITN"
		(exclude_from_sim no)
		(at 360.68 195.58 0)
		(effects
			(font
				(size 3 3)
			)
			(justify left bottom)
		)
	)
	(text "PROGRAMN"
		(exclude_from_sim no)
		(at 224.79 189.23 0)
		(effects
			(font
				(size 3 3)
			)
			(justify left bottom)
		)
	)
	(junction
		(at 336.55 39.37)
		(diameter 0)
		(color 0 0 0 0)
	)
	(junction
		(at 140.97 152.4)
		(diameter 0)
		(color 0 0 0 0)
	)
	(junction
		(at 350.52 66.04)
		(diameter 0)
		(color 0 0 0 0)
	)
	(junction
		(at 316.23 203.2)
		(diameter 0)
		(color 0 0 0 0)
	)
	(junction
		(at 290.83 55.88)
		(diameter 0)
		(color 0 0 0 0)
	)
	(junction
		(at 302.26 63.5)
		(diameter 0)
		(color 0 0 0 0)
	)
	(junction
		(at 361.95 229.87)
		(diameter 0)
		(color 0 0 0 0)
	)
	(junction
		(at 91.44 140.97)
		(diameter 0)
		(color 0 0 0 0)
	)
	(junction
		(at 142.24 53.34)
		(diameter 0)
		(color 0 0 0 0)
	)
	(junction
		(at 320.04 66.04)
		(diameter 0)
		(color 0 0 0 0)
	)
	(junction
		(at 289.56 55.88)
		(diameter 0)
		(color 0 0 0 0)
	)
	(junction
		(at 140.97 143.51)
		(diameter 0)
		(color 0 0 0 0)
	)
	(junction
		(at 356.87 229.87)
		(diameter 0)
		(color 0 0 0 0)
	)
	(junction
		(at 317.5 39.37)
		(diameter 0)
		(color 0 0 0 0)
	)
	(junction
		(at 142.24 257.81)
		(diameter 0)
		(color 0 0 0 0)
	)
	(junction
		(at 317.5 60.96)
		(diameter 0)
		(color 0 0 0 0)
	)
	(junction
		(at 284.48 229.87)
		(diameter 0)
		(color 0 0 0 0)
	)
	(junction
		(at 304.8 66.04)
		(diameter 0)
		(color 0 0 0 0)
	)
	(junction
		(at 140.97 146.05)
		(diameter 0)
		(color 0 0 0 0)
	)
	(junction
		(at 91.44 149.86)
		(diameter 0)
		(color 0 0 0 0)
	)
	(junction
		(at 361.95 203.2)
		(diameter 0)
		(color 0 0 0 0)
	)
	(junction
		(at 287.02 53.34)
		(diameter 0)
		(color 0 0 0 0)
	)
	(junction
		(at 300.99 63.5)
		(diameter 0)
		(color 0 0 0 0)
	)
	(junction
		(at 234.95 226.06)
		(diameter 0)
		(color 0 0 0 0)
	)
	(junction
		(at 251.46 134.62)
		(diameter 0)
		(color 0 0 0 0)
	)
	(junction
		(at 224.79 215.9)
		(diameter 0)
		(color 0 0 0 0)
	)
	(junction
		(at 252.73 83.82)
		(diameter 0)
		(color 0 0 0 0)
	)
	(junction
		(at 285.75 53.34)
		(diameter 0)
		(color 0 0 0 0)
	)
	(junction
		(at 293.37 229.87)
		(diameter 0)
		(color 0 0 0 0)
	)
	(junction
		(at 91.44 143.51)
		(diameter 0)
		(color 0 0 0 0)
	)
	(junction
		(at 349.25 123.19)
		(diameter 0)
		(color 0 0 0 0)
	)
	(junction
		(at 293.37 58.42)
		(diameter 0)
		(color 0 0 0 0)
	)
	(junction
		(at 309.88 58.42)
		(diameter 0)
		(color 0 0 0 0)
	)
	(junction
		(at 91.44 153.67)
		(diameter 0)
		(color 0 0 0 0)
	)
	(junction
		(at 349.25 118.11)
		(diameter 0)
		(color 0 0 0 0)
	)
	(junction
		(at 91.44 147.32)
		(diameter 0)
		(color 0 0 0 0)
	)
	(junction
		(at 288.29 229.87)
		(diameter 0)
		(color 0 0 0 0)
	)
	(junction
		(at 297.18 60.96)
		(diameter 0)
		(color 0 0 0 0)
	)
	(junction
		(at 91.44 137.16)
		(diameter 0)
		(color 0 0 0 0)
	)
	(junction
		(at 140.97 133.35)
		(diameter 0)
		(color 0 0 0 0)
	)
	(junction
		(at 350.52 53.34)
		(diameter 0)
		(color 0 0 0 0)
	)
	(junction
		(at 370.84 229.87)
		(diameter 0)
		(color 0 0 0 0)
	)
	(junction
		(at 378.46 125.73)
		(diameter 0)
		(color 0 0 0 0)
	)
	(junction
		(at 325.12 66.04)
		(diameter 0)
		(color 0 0 0 0)
	)
	(junction
		(at 325.12 39.37)
		(diameter 0)
		(color 0 0 0 0)
	)
	(no_connect
		(at 88.9 130.81)
	)
	(no_connect
		(at 351.79 120.65)
	)
	(no_connect
		(at 138.43 139.7)
	)
	(no_connect
		(at 138.43 149.86)
	)
	(no_connect
		(at 138.43 137.16)
	)
	(no_connect
		(at 118.11 78.74)
	)
	(wire
		(pts
			(xy 293.37 203.2) (xy 293.37 214.63)
		)
		(stroke
			(width 0)
			(type default)
		)
	)
	(wire
		(pts
			(xy 212.09 58.42) (xy 228.6 58.42)
		)
		(stroke
			(width 0)
			(type default)
		)
	)
	(wire
		(pts
			(xy 252.73 83.82) (xy 251.46 83.82)
		)
		(stroke
			(width 0)
			(type default)
		)
	)
	(wire
		(pts
			(xy 316.23 203.2) (xy 316.23 205.74)
		)
		(stroke
			(width 0)
			(type default)
		)
	)
	(wire
		(pts
			(xy 349.25 113.03) (xy 351.79 113.03)
		)
		(stroke
			(width 0)
			(type default)
		)
	)
	(wire
		(pts
			(xy 243.84 123.19) (xy 243.84 127)
		)
		(stroke
			(width 0)
			(type default)
		)
	)
	(wire
		(pts
			(xy 309.88 58.42) (xy 330.2 58.42)
		)
		(stroke
			(width 0)
			(type default)
		)
	)
	(wire
		(pts
			(xy 284.48 82.55) (xy 302.26 82.55)
		)
		(stroke
			(width 0)
			(type default)
		)
	)
	(wire
		(pts
			(xy 252.73 83.82) (xy 257.81 83.82)
		)
		(stroke
			(width 0)
			(type default)
		)
	)
	(wire
		(pts
			(xy 325.12 46.99) (xy 325.12 66.04)
		)
		(stroke
			(width 0)
			(type default)
		)
	)
	(wire
		(pts
			(xy 252.73 90.17) (xy 252.73 88.9)
		)
		(stroke
			(width 0)
			(type default)
		)
	)
	(wire
		(pts
			(xy 356.87 229.87) (xy 356.87 236.22)
		)
		(stroke
			(width 0)
			(type default)
		)
	)
	(wire
		(pts
			(xy 138.43 146.05) (xy 140.97 146.05)
		)
		(stroke
			(width 0)
			(type default)
		)
	)
	(wire
		(pts
			(xy 240.03 123.19) (xy 240.03 127)
		)
		(stroke
			(width 0)
			(type default)
		)
	)
	(wire
		(pts
			(xy 233.68 163.83) (xy 233.68 165.1)
		)
		(stroke
			(width 0)
			(type default)
		)
	)
	(wire
		(pts
			(xy 209.55 215.9) (xy 224.79 215.9)
		)
		(stroke
			(width 0)
			(type default)
		)
	)
	(wire
		(pts
			(xy 336.55 38.1) (xy 336.55 39.37)
		)
		(stroke
			(width 0)
			(type default)
		)
	)
	(wire
		(pts
			(xy 350.52 62.23) (xy 350.52 66.04)
		)
		(stroke
			(width 0)
			(type default)
		)
	)
	(wire
		(pts
			(xy 226.06 163.83) (xy 226.06 165.1)
		)
		(stroke
			(width 0)
			(type default)
		)
	)
	(wire
		(pts
			(xy 361.95 113.03) (xy 363.22 113.03)
		)
		(stroke
			(width 0)
			(type default)
		)
	)
	(wire
		(pts
			(xy 243.84 132.08) (xy 243.84 142.24)
		)
		(stroke
			(width 0)
			(type default)
		)
	)
	(wire
		(pts
			(xy 290.83 55.88) (xy 330.2 55.88)
		)
		(stroke
			(width 0)
			(type default)
		)
	)
	(wire
		(pts
			(xy 257.81 45.72) (xy 251.46 45.72)
		)
		(stroke
			(width 0)
			(type default)
		)
	)
	(wire
		(pts
			(xy 140.97 146.05) (xy 140.97 143.51)
		)
		(stroke
			(width 0)
			(type default)
		)
	)
	(wire
		(pts
			(xy 378.46 125.73) (xy 379.73 125.73)
		)
		(stroke
			(width 0)
			(type default)
		)
	)
	(wire
		(pts
			(xy 363.22 113.03) (xy 363.22 105.41)
		)
		(stroke
			(width 0)
			(type default)
		)
	)
	(wire
		(pts
			(xy 285.75 144.78) (xy 299.72 144.78)
		)
		(stroke
			(width 0)
			(type default)
		)
	)
	(wire
		(pts
			(xy 365.76 236.22) (xy 381 236.22)
		)
		(stroke
			(width 0)
			(type default)
		)
	)
	(wire
		(pts
			(xy 364.49 123.19) (xy 364.49 125.73)
		)
		(stroke
			(width 0)
			(type default)
		)
	)
	(wire
		(pts
			(xy 132.08 71.12) (xy 118.11 71.12)
		)
		(stroke
			(width 0)
			(type default)
		)
	)
	(wire
		(pts
			(xy 256.54 160.02) (xy 256.54 165.1)
		)
		(stroke
			(width 0)
			(type default)
		)
	)
	(wire
		(pts
			(xy 142.24 257.81) (xy 142.24 262.89)
		)
		(stroke
			(width 0)
			(type default)
		)
	)
	(wire
		(pts
			(xy 378.46 133.35) (xy 378.46 134.62)
		)
		(stroke
			(width 0)
			(type default)
		)
	)
	(wire
		(pts
			(xy 364.49 115.57) (xy 364.49 110.49)
		)
		(stroke
			(width 0)
			(type default)
		)
	)
	(wire
		(pts
			(xy 375.92 110.49) (xy 379.73 110.49)
		)
		(stroke
			(width 0)
			(type default)
		)
	)
	(wire
		(pts
			(xy 361.95 219.71) (xy 361.95 229.87)
		)
		(stroke
			(width 0)
			(type default)
		)
	)
	(wire
		(pts
			(xy 285.75 149.86) (xy 312.42 149.86)
		)
		(stroke
			(width 0)
			(type default)
		)
	)
	(wire
		(pts
			(xy 285.75 50.8) (xy 285.75 53.34)
		)
		(stroke
			(width 0)
			(type default)
		)
	)
	(wire
		(pts
			(xy 142.24 53.34) (xy 142.24 59.69)
		)
		(stroke
			(width 0)
			(type default)
		)
	)
	(wire
		(pts
			(xy 350.52 229.87) (xy 356.87 229.87)
		)
		(stroke
			(width 0)
			(type default)
		)
	)
	(wire
		(pts
			(xy 361.95 123.19) (xy 364.49 123.19)
		)
		(stroke
			(width 0)
			(type default)
		)
	)
	(wire
		(pts
			(xy 251.46 123.19) (xy 251.46 134.62)
		)
		(stroke
			(width 0)
			(type default)
		)
	)
	(wire
		(pts
			(xy 91.44 153.67) (xy 91.44 156.21)
		)
		(stroke
			(width 0)
			(type default)
		)
	)
	(wire
		(pts
			(xy 260.35 76.2) (xy 251.46 76.2)
		)
		(stroke
			(width 0)
			(type default)
		)
	)
	(wire
		(pts
			(xy 287.02 53.34) (xy 330.2 53.34)
		)
		(stroke
			(width 0)
			(type default)
		)
	)
	(wire
		(pts
			(xy 262.89 77.47) (xy 279.4 77.47)
		)
		(stroke
			(width 0)
			(type default)
		)
	)
	(wire
		(pts
			(xy 226.06 152.4) (xy 226.06 158.75)
		)
		(stroke
			(width 0)
			(type default)
		)
	)
	(wire
		(pts
			(xy 132.08 66.04) (xy 118.11 66.04)
		)
		(stroke
			(width 0)
			(type default)
		)
	)
	(wire
		(pts
			(xy 304.8 50.8) (xy 304.8 66.04)
		)
		(stroke
			(width 0)
			(type default)
		)
	)
	(wire
		(pts
			(xy 224.79 215.9) (xy 224.79 226.06)
		)
		(stroke
			(width 0)
			(type default)
		)
	)
	(wire
		(pts
			(xy 349.25 118.11) (xy 349.25 115.57)
		)
		(stroke
			(width 0)
			(type default)
		)
	)
	(wire
		(pts
			(xy 91.44 143.51) (xy 91.44 147.32)
		)
		(stroke
			(width 0)
			(type default)
		)
	)
	(wire
		(pts
			(xy 309.88 46.99) (xy 309.88 58.42)
		)
		(stroke
			(width 0)
			(type default)
		)
	)
	(wire
		(pts
			(xy 260.35 66.04) (xy 304.8 66.04)
		)
		(stroke
			(width 0)
			(type default)
		)
	)
	(wire
		(pts
			(xy 132.08 58.42) (xy 118.11 58.42)
		)
		(stroke
			(width 0)
			(type default)
		)
	)
	(wire
		(pts
			(xy 212.09 63.5) (xy 228.6 63.5)
		)
		(stroke
			(width 0)
			(type default)
		)
	)
	(wire
		(pts
			(xy 317.5 39.37) (xy 325.12 39.37)
		)
		(stroke
			(width 0)
			(type default)
		)
	)
	(wire
		(pts
			(xy 257.81 53.34) (xy 285.75 53.34)
		)
		(stroke
			(width 0)
			(type default)
		)
	)
	(wire
		(pts
			(xy 226.06 144.78) (xy 228.6 144.78)
		)
		(stroke
			(width 0)
			(type default)
		)
	)
	(wire
		(pts
			(xy 257.81 53.34) (xy 257.81 45.72)
		)
		(stroke
			(width 0)
			(type default)
		)
	)
	(wire
		(pts
			(xy 375.92 115.57) (xy 379.73 115.57)
		)
		(stroke
			(width 0)
			(type default)
		)
	)
	(wire
		(pts
			(xy 251.46 163.83) (xy 251.46 165.1)
		)
		(stroke
			(width 0)
			(type default)
		)
	)
	(wire
		(pts
			(xy 242.57 226.06) (xy 251.46 226.06)
		)
		(stroke
			(width 0)
			(type default)
		)
	)
	(wire
		(pts
			(xy 257.81 63.5) (xy 257.81 66.04)
		)
		(stroke
			(width 0)
			(type default)
		)
	)
	(wire
		(pts
			(xy 317.5 66.04) (xy 320.04 66.04)
		)
		(stroke
			(width 0)
			(type default)
		)
	)
	(wire
		(pts
			(xy 132.08 68.58) (xy 118.11 68.58)
		)
		(stroke
			(width 0)
			(type default)
		)
	)
	(polyline
		(pts
			(xy 198.12 219.71) (xy 120.65 219.71)
		)
		(stroke
			(width 0)
			(type default)
		)
	)
	(polyline
		(pts
			(xy 120.65 219.71) (xy 120.65 284.48)
		)
		(stroke
			(width 0)
			(type default)
		)
	)
	(wire
		(pts
			(xy 349.25 115.57) (xy 351.79 115.57)
		)
		(stroke
			(width 0)
			(type default)
		)
	)
	(wire
		(pts
			(xy 309.88 39.37) (xy 309.88 41.91)
		)
		(stroke
			(width 0)
			(type default)
		)
	)
	(wire
		(pts
			(xy 370.84 229.87) (xy 379.73 229.87)
		)
		(stroke
			(width 0)
			(type default)
		)
	)
	(wire
		(pts
			(xy 88.9 134.62) (xy 91.44 134.62)
		)
		(stroke
			(width 0)
			(type default)
		)
	)
	(wire
		(pts
			(xy 234.95 234.95) (xy 234.95 236.22)
		)
		(stroke
			(width 0)
			(type default)
		)
	)
	(wire
		(pts
			(xy 356.87 236.22) (xy 360.68 236.22)
		)
		(stroke
			(width 0)
			(type default)
		)
	)
	(wire
		(pts
			(xy 212.09 73.66) (xy 228.6 73.66)
		)
		(stroke
			(width 0)
			(type default)
		)
	)
	(wire
		(pts
			(xy 293.37 50.8) (xy 293.37 58.42)
		)
		(stroke
			(width 0)
			(type default)
		)
	)
	(wire
		(pts
			(xy 224.79 226.06) (xy 227.33 226.06)
		)
		(stroke
			(width 0)
			(type default)
		)
	)
	(wire
		(pts
			(xy 88.9 140.97) (xy 91.44 140.97)
		)
		(stroke
			(width 0)
			(type default)
		)
	)
	(wire
		(pts
			(xy 349.25 53.34) (xy 350.52 53.34)
		)
		(stroke
			(width 0)
			(type default)
		)
	)
	(wire
		(pts
			(xy 287.02 72.39) (xy 287.02 53.34)
		)
		(stroke
			(width 0)
			(type default)
		)
	)
	(wire
		(pts
			(xy 234.95 226.06) (xy 234.95 229.87)
		)
		(stroke
			(width 0)
			(type default)
		)
	)
	(wire
		(pts
			(xy 361.95 203.2) (xy 361.95 214.63)
		)
		(stroke
			(width 0)
			(type default)
		)
	)
	(wire
		(pts
			(xy 288.29 229.87) (xy 293.37 229.87)
		)
		(stroke
			(width 0)
			(type default)
		)
	)
	(wire
		(pts
			(xy 88.9 149.86) (xy 91.44 149.86)
		)
		(stroke
			(width 0)
			(type default)
		)
	)
	(wire
		(pts
			(xy 134.62 260.35) (xy 148.59 260.35)
		)
		(stroke
			(width 0)
			(type default)
		)
	)
	(wire
		(pts
			(xy 212.09 48.26) (xy 228.6 48.26)
		)
		(stroke
			(width 0)
			(type default)
		)
	)
	(wire
		(pts
			(xy 142.24 251.46) (xy 142.24 257.81)
		)
		(stroke
			(width 0)
			(type default)
		)
	)
	(wire
		(pts
			(xy 251.46 134.62) (xy 257.81 134.62)
		)
		(stroke
			(width 0)
			(type default)
		)
	)
	(wire
		(pts
			(xy 349.25 123.19) (xy 349.25 118.11)
		)
		(stroke
			(width 0)
			(type default)
		)
	)
	(wire
		(pts
			(xy 370.84 203.2) (xy 370.84 210.82)
		)
		(stroke
			(width 0)
			(type default)
		)
	)
	(wire
		(pts
			(xy 167.64 257.81) (xy 168.91 257.81)
		)
		(stroke
			(width 0)
			(type default)
		)
	)
	(wire
		(pts
			(xy 361.95 201.93) (xy 361.95 203.2)
		)
		(stroke
			(width 0)
			(type default)
		)
	)
	(wire
		(pts
			(xy 251.46 238.76) (xy 251.46 240.03)
		)
		(stroke
			(width 0)
			(type default)
		)
	)
	(wire
		(pts
			(xy 138.43 152.4) (xy 140.97 152.4)
		)
		(stroke
			(width 0)
			(type default)
		)
	)
	(wire
		(pts
			(xy 140.97 152.4) (xy 140.97 153.67)
		)
		(stroke
			(width 0)
			(type default)
		)
	)
	(wire
		(pts
			(xy 257.81 137.16) (xy 240.03 137.16)
		)
		(stroke
			(width 0)
			(type default)
		)
	)
	(wire
		(pts
			(xy 298.45 157.48) (xy 312.42 157.48)
		)
		(stroke
			(width 0)
			(type default)
		)
	)
	(wire
		(pts
			(xy 278.13 229.87) (xy 284.48 229.87)
		)
		(stroke
			(width 0)
			(type default)
		)
	)
	(wire
		(pts
			(xy 132.08 73.66) (xy 118.11 73.66)
		)
		(stroke
			(width 0)
			(type default)
		)
	)
	(wire
		(pts
			(xy 142.24 50.8) (xy 142.24 53.34)
		)
		(stroke
			(width 0)
			(type default)
		)
	)
	(wire
		(pts
			(xy 257.81 91.44) (xy 257.81 92.71)
		)
		(stroke
			(width 0)
			(type default)
		)
	)
	(wire
		(pts
			(xy 212.09 43.18) (xy 228.6 43.18)
		)
		(stroke
			(width 0)
			(type default)
		)
	)
	(wire
		(pts
			(xy 285.75 152.4) (xy 312.42 152.4)
		)
		(stroke
			(width 0)
			(type default)
		)
	)
	(wire
		(pts
			(xy 140.97 130.81) (xy 140.97 133.35)
		)
		(stroke
			(width 0)
			(type default)
		)
	)
	(wire
		(pts
			(xy 227.33 88.9) (xy 228.6 88.9)
		)
		(stroke
			(width 0)
			(type default)
		)
	)
	(wire
		(pts
			(xy 212.09 78.74) (xy 228.6 78.74)
		)
		(stroke
			(width 0)
			(type default)
		)
	)
	(wire
		(pts
			(xy 378.46 125.73) (xy 378.46 128.27)
		)
		(stroke
			(width 0)
			(type default)
		)
	)
	(wire
		(pts
			(xy 297.18 60.96) (xy 317.5 60.96)
		)
		(stroke
			(width 0)
			(type default)
		)
	)
	(wire
		(pts
			(xy 226.06 152.4) (xy 257.81 152.4)
		)
		(stroke
			(width 0)
			(type default)
		)
	)
	(wire
		(pts
			(xy 284.48 87.63) (xy 320.04 87.63)
		)
		(stroke
			(width 0)
			(type default)
		)
	)
	(wire
		(pts
			(xy 147.32 269.24) (xy 147.32 262.89)
		)
		(stroke
			(width 0)
			(type default)
		)
	)
	(wire
		(pts
			(xy 132.08 76.2) (xy 118.11 76.2)
		)
		(stroke
			(width 0)
			(type default)
		)
	)
	(wire
		(pts
			(xy 120.65 81.28) (xy 118.11 81.28)
		)
		(stroke
			(width 0)
			(type default)
		)
	)
	(wire
		(pts
			(xy 320.04 87.63) (xy 320.04 66.04)
		)
		(stroke
			(width 0)
			(type default)
		)
	)
	(wire
		(pts
			(xy 364.49 110.49) (xy 370.84 110.49)
		)
		(stroke
			(width 0)
			(type default)
		)
	)
	(wire
		(pts
			(xy 289.56 55.88) (xy 290.83 55.88)
		)
		(stroke
			(width 0)
			(type default)
		)
	)
	(wire
		(pts
			(xy 147.32 262.89) (xy 148.59 262.89)
		)
		(stroke
			(width 0)
			(type default)
		)
	)
	(wire
		(pts
			(xy 233.68 144.78) (xy 257.81 144.78)
		)
		(stroke
			(width 0)
			(type default)
		)
	)
	(wire
		(pts
			(xy 257.81 142.24) (xy 243.84 142.24)
		)
		(stroke
			(width 0)
			(type default)
		)
	)
	(wire
		(pts
			(xy 132.08 63.5) (xy 118.11 63.5)
		)
		(stroke
			(width 0)
			(type default)
		)
	)
	(wire
		(pts
			(xy 251.46 226.06) (xy 251.46 228.6)
		)
		(stroke
			(width 0)
			(type default)
		)
	)
	(wire
		(pts
			(xy 140.97 143.51) (xy 138.43 143.51)
		)
		(stroke
			(width 0)
			(type default)
		)
	)
	(wire
		(pts
			(xy 88.9 137.16) (xy 91.44 137.16)
		)
		(stroke
			(width 0)
			(type default)
		)
	)
	(wire
		(pts
			(xy 293.37 203.2) (xy 316.23 203.2)
		)
		(stroke
			(width 0)
			(type default)
		)
	)
	(wire
		(pts
			(xy 304.8 66.04) (xy 312.42 66.04)
		)
		(stroke
			(width 0)
			(type default)
		)
	)
	(wire
		(pts
			(xy 336.55 39.37) (xy 350.52 39.37)
		)
		(stroke
			(width 0)
			(type default)
		)
	)
	(wire
		(pts
			(xy 233.68 154.94) (xy 233.68 158.75)
		)
		(stroke
			(width 0)
			(type default)
		)
	)
	(wire
		(pts
			(xy 262.89 60.96) (xy 297.18 60.96)
		)
		(stroke
			(width 0)
			(type default)
		)
	)
	(wire
		(pts
			(xy 212.09 53.34) (xy 228.6 53.34)
		)
		(stroke
			(width 0)
			(type default)
		)
	)
	(wire
		(pts
			(xy 262.89 82.55) (xy 279.4 82.55)
		)
		(stroke
			(width 0)
			(type default)
		)
	)
	(wire
		(pts
			(xy 91.44 140.97) (xy 91.44 143.51)
		)
		(stroke
			(width 0)
			(type default)
		)
	)
	(wire
		(pts
			(xy 356.87 229.87) (xy 361.95 229.87)
		)
		(stroke
			(width 0)
			(type default)
		)
	)
	(wire
		(pts
			(xy 289.56 50.8) (xy 289.56 55.88)
		)
		(stroke
			(width 0)
			(type default)
		)
	)
	(wire
		(pts
			(xy 251.46 55.88) (xy 289.56 55.88)
		)
		(stroke
			(width 0)
			(type default)
		)
	)
	(wire
		(pts
			(xy 256.54 160.02) (xy 257.81 160.02)
		)
		(stroke
			(width 0)
			(type default)
		)
	)
	(wire
		(pts
			(xy 88.9 143.51) (xy 91.44 143.51)
		)
		(stroke
			(width 0)
			(type default)
		)
	)
	(wire
		(pts
			(xy 370.84 215.9) (xy 370.84 219.71)
		)
		(stroke
			(width 0)
			(type default)
		)
	)
	(wire
		(pts
			(xy 212.09 83.82) (xy 228.6 83.82)
		)
		(stroke
			(width 0)
			(type default)
		)
	)
	(wire
		(pts
			(xy 293.37 219.71) (xy 293.37 229.87)
		)
		(stroke
			(width 0)
			(type default)
		)
	)
	(wire
		(pts
			(xy 351.79 123.19) (xy 349.25 123.19)
		)
		(stroke
			(width 0)
			(type default)
		)
	)
	(wire
		(pts
			(xy 252.73 82.55) (xy 252.73 83.82)
		)
		(stroke
			(width 0)
			(type default)
		)
	)
	(wire
		(pts
			(xy 370.84 229.87) (xy 370.84 224.79)
		)
		(stroke
			(width 0)
			(type default)
		)
	)
	(wire
		(pts
			(xy 349.25 110.49) (xy 349.25 113.03)
		)
		(stroke
			(width 0)
			(type default)
		)
	)
	(wire
		(pts
			(xy 317.5 39.37) (xy 317.5 41.91)
		)
		(stroke
			(width 0)
			(type default)
		)
	)
	(wire
		(pts
			(xy 293.37 236.22) (xy 306.07 236.22)
		)
		(stroke
			(width 0)
			(type default)
		)
	)
	(wire
		(pts
			(xy 262.89 87.63) (xy 279.4 87.63)
		)
		(stroke
			(width 0)
			(type default)
		)
	)
	(wire
		(pts
			(xy 351.79 118.11) (xy 349.25 118.11)
		)
		(stroke
			(width 0)
			(type default)
		)
	)
	(wire
		(pts
			(xy 120.65 83.82) (xy 118.11 83.82)
		)
		(stroke
			(width 0)
			(type default)
		)
	)
	(wire
		(pts
			(xy 316.23 201.93) (xy 316.23 203.2)
		)
		(stroke
			(width 0)
			(type default)
		)
	)
	(wire
		(pts
			(xy 285.75 139.7) (xy 299.72 139.7)
		)
		(stroke
			(width 0)
			(type default)
		)
	)
	(wire
		(pts
			(xy 290.83 77.47) (xy 290.83 55.88)
		)
		(stroke
			(width 0)
			(type default)
		)
	)
	(wire
		(pts
			(xy 240.03 137.16) (xy 240.03 132.08)
		)
		(stroke
			(width 0)
			(type default)
		)
	)
	(wire
		(pts
			(xy 241.3 163.83) (xy 241.3 165.1)
		)
		(stroke
			(width 0)
			(type default)
		)
	)
	(wire
		(pts
			(xy 241.3 157.48) (xy 257.81 157.48)
		)
		(stroke
			(width 0)
			(type default)
		)
	)
	(wire
		(pts
			(xy 284.48 77.47) (xy 290.83 77.47)
		)
		(stroke
			(width 0)
			(type default)
		)
	)
	(wire
		(pts
			(xy 300.99 50.8) (xy 300.99 63.5)
		)
		(stroke
			(width 0)
			(type default)
		)
	)
	(wire
		(pts
			(xy 284.48 236.22) (xy 288.29 236.22)
		)
		(stroke
			(width 0)
			(type default)
		)
	)
	(wire
		(pts
			(xy 349.25 123.19) (xy 349.25 134.62)
		)
		(stroke
			(width 0)
			(type default)
		)
	)
	(wire
		(pts
			(xy 302.26 63.5) (xy 330.2 63.5)
		)
		(stroke
			(width 0)
			(type default)
		)
	)
	(wire
		(pts
			(xy 88.9 147.32) (xy 91.44 147.32)
		)
		(stroke
			(width 0)
			(type default)
		)
	)
	(wire
		(pts
			(xy 232.41 226.06) (xy 234.95 226.06)
		)
		(stroke
			(width 0)
			(type default)
		)
	)
	(wire
		(pts
			(xy 118.11 53.34) (xy 142.24 53.34)
		)
		(stroke
			(width 0)
			(type default)
		)
	)
	(wire
		(pts
			(xy 325.12 66.04) (xy 330.2 66.04)
		)
		(stroke
			(width 0)
			(type default)
		)
	)
	(wire
		(pts
			(xy 262.89 58.42) (xy 293.37 58.42)
		)
		(stroke
			(width 0)
			(type default)
		)
	)
	(wire
		(pts
			(xy 233.68 154.94) (xy 257.81 154.94)
		)
		(stroke
			(width 0)
			(type default)
		)
	)
	(wire
		(pts
			(xy 364.49 125.73) (xy 370.84 125.73)
		)
		(stroke
			(width 0)
			(type default)
		)
	)
	(wire
		(pts
			(xy 142.24 267.97) (xy 142.24 269.24)
		)
		(stroke
			(width 0)
			(type default)
		)
	)
	(wire
		(pts
			(xy 257.81 63.5) (xy 300.99 63.5)
		)
		(stroke
			(width 0)
			(type default)
		)
	)
	(wire
		(pts
			(xy 304.8 229.87) (xy 308.61 229.87)
		)
		(stroke
			(width 0)
			(type default)
		)
	)
	(wire
		(pts
			(xy 316.23 218.44) (xy 316.23 220.98)
		)
		(stroke
			(width 0)
			(type default)
		)
	)
	(wire
		(pts
			(xy 134.62 257.81) (xy 134.62 260.35)
		)
		(stroke
			(width 0)
			(type default)
		)
	)
	(wire
		(pts
			(xy 368.3 115.57) (xy 370.84 115.57)
		)
		(stroke
			(width 0)
			(type default)
		)
	)
	(wire
		(pts
			(xy 212.09 68.58) (xy 228.6 68.58)
		)
		(stroke
			(width 0)
			(type default)
		)
	)
	(wire
		(pts
			(xy 297.18 50.8) (xy 297.18 60.96)
		)
		(stroke
			(width 0)
			(type default)
		)
	)
	(wire
		(pts
			(xy 91.44 137.16) (xy 91.44 140.97)
		)
		(stroke
			(width 0)
			(type default)
		)
	)
	(wire
		(pts
			(xy 316.23 210.82) (xy 316.23 213.36)
		)
		(stroke
			(width 0)
			(type default)
		)
	)
	(wire
		(pts
			(xy 361.95 203.2) (xy 370.84 203.2)
		)
		(stroke
			(width 0)
			(type default)
		)
	)
	(wire
		(pts
			(xy 350.52 66.04) (xy 349.25 66.04)
		)
		(stroke
			(width 0)
			(type default)
		)
	)
	(wire
		(pts
			(xy 138.43 130.81) (xy 140.97 130.81)
		)
		(stroke
			(width 0)
			(type default)
		)
	)
	(wire
		(pts
			(xy 293.37 58.42) (xy 309.88 58.42)
		)
		(stroke
			(width 0)
			(type default)
		)
	)
	(wire
		(pts
			(xy 325.12 39.37) (xy 325.12 41.91)
		)
		(stroke
			(width 0)
			(type default)
		)
	)
	(wire
		(pts
			(xy 285.75 53.34) (xy 287.02 53.34)
		)
		(stroke
			(width 0)
			(type default)
		)
	)
	(wire
		(pts
			(xy 262.89 72.39) (xy 279.4 72.39)
		)
		(stroke
			(width 0)
			(type default)
		)
	)
	(wire
		(pts
			(xy 368.3 118.11) (xy 368.3 115.57)
		)
		(stroke
			(width 0)
			(type default)
		)
	)
	(wire
		(pts
			(xy 363.22 105.41) (xy 370.84 105.41)
		)
		(stroke
			(width 0)
			(type default)
		)
	)
	(wire
		(pts
			(xy 309.88 39.37) (xy 317.5 39.37)
		)
		(stroke
			(width 0)
			(type default)
		)
	)
	(wire
		(pts
			(xy 361.95 118.11) (xy 368.3 118.11)
		)
		(stroke
			(width 0)
			(type default)
		)
	)
	(wire
		(pts
			(xy 91.44 134.62) (xy 91.44 137.16)
		)
		(stroke
			(width 0)
			(type default)
		)
	)
	(wire
		(pts
			(xy 88.9 153.67) (xy 91.44 153.67)
		)
		(stroke
			(width 0)
			(type default)
		)
	)
	(wire
		(pts
			(xy 142.24 257.81) (xy 148.59 257.81)
		)
		(stroke
			(width 0)
			(type default)
		)
	)
	(wire
		(pts
			(xy 260.35 66.04) (xy 260.35 76.2)
		)
		(stroke
			(width 0)
			(type default)
		)
	)
	(wire
		(pts
			(xy 361.95 120.65) (xy 370.84 120.65)
		)
		(stroke
			(width 0)
			(type default)
		)
	)
	(wire
		(pts
			(xy 132.08 60.96) (xy 118.11 60.96)
		)
		(stroke
			(width 0)
			(type default)
		)
	)
	(wire
		(pts
			(xy 302.26 82.55) (xy 302.26 63.5)
		)
		(stroke
			(width 0)
			(type default)
		)
	)
	(wire
		(pts
			(xy 317.5 46.99) (xy 317.5 60.96)
		)
		(stroke
			(width 0)
			(type default)
		)
	)
	(wire
		(pts
			(xy 325.12 39.37) (xy 336.55 39.37)
		)
		(stroke
			(width 0)
			(type default)
		)
	)
	(wire
		(pts
			(xy 140.97 133.35) (xy 140.97 143.51)
		)
		(stroke
			(width 0)
			(type default)
		)
	)
	(wire
		(pts
			(xy 257.81 66.04) (xy 251.46 66.04)
		)
		(stroke
			(width 0)
			(type default)
		)
	)
	(wire
		(pts
			(xy 350.52 68.58) (xy 350.52 66.04)
		)
		(stroke
			(width 0)
			(type default)
		)
	)
	(wire
		(pts
			(xy 140.97 152.4) (xy 140.97 146.05)
		)
		(stroke
			(width 0)
			(type default)
		)
	)
	(wire
		(pts
			(xy 285.75 157.48) (xy 293.37 157.48)
		)
		(stroke
			(width 0)
			(type default)
		)
	)
	(wire
		(pts
			(xy 226.06 147.32) (xy 228.6 147.32)
		)
		(stroke
			(width 0)
			(type default)
		)
	)
	(wire
		(pts
			(xy 234.95 226.06) (xy 237.49 226.06)
		)
		(stroke
			(width 0)
			(type default)
		)
	)
	(wire
		(pts
			(xy 375.92 120.65) (xy 379.73 120.65)
		)
		(stroke
			(width 0)
			(type default)
		)
	)
	(wire
		(pts
			(xy 298.45 154.94) (xy 312.42 154.94)
		)
		(stroke
			(width 0)
			(type default)
		)
	)
	(wire
		(pts
			(xy 252.73 88.9) (xy 251.46 88.9)
		)
		(stroke
			(width 0)
			(type default)
		)
	)
	(wire
		(pts
			(xy 300.99 63.5) (xy 302.26 63.5)
		)
		(stroke
			(width 0)
			(type default)
		)
	)
	(wire
		(pts
			(xy 91.44 149.86) (xy 91.44 153.67)
		)
		(stroke
			(width 0)
			(type default)
		)
	)
	(wire
		(pts
			(xy 316.23 233.68) (xy 316.23 234.95)
		)
		(stroke
			(width 0)
			(type default)
		)
	)
	(wire
		(pts
			(xy 361.95 115.57) (xy 364.49 115.57)
		)
		(stroke
			(width 0)
			(type default)
		)
	)
	(wire
		(pts
			(xy 293.37 229.87) (xy 299.72 229.87)
		)
		(stroke
			(width 0)
			(type default)
		)
	)
	(wire
		(pts
			(xy 284.48 229.87) (xy 288.29 229.87)
		)
		(stroke
			(width 0)
			(type default)
		)
	)
	(wire
		(pts
			(xy 317.5 60.96) (xy 330.2 60.96)
		)
		(stroke
			(width 0)
			(type default)
		)
	)
	(wire
		(pts
			(xy 91.44 147.32) (xy 91.44 149.86)
		)
		(stroke
			(width 0)
			(type default)
		)
	)
	(polyline
		(pts
			(xy 198.12 12.7) (xy 198.12 284.48)
		)
		(stroke
			(width 0)
			(type default)
		)
	)
	(wire
		(pts
			(xy 375.92 125.73) (xy 378.46 125.73)
		)
		(stroke
			(width 0)
			(type default)
		)
	)
	(wire
		(pts
			(xy 299.72 142.24) (xy 285.75 142.24)
		)
		(stroke
			(width 0)
			(type default)
		)
	)
	(wire
		(pts
			(xy 288.29 226.06) (xy 288.29 229.87)
		)
		(stroke
			(width 0)
			(type default)
		)
	)
	(wire
		(pts
			(xy 284.48 72.39) (xy 287.02 72.39)
		)
		(stroke
			(width 0)
			(type default)
		)
	)
	(wire
		(pts
			(xy 251.46 134.62) (xy 251.46 158.75)
		)
		(stroke
			(width 0)
			(type default)
		)
	)
	(wire
		(pts
			(xy 350.52 53.34) (xy 350.52 39.37)
		)
		(stroke
			(width 0)
			(type default)
		)
	)
	(wire
		(pts
			(xy 361.95 229.87) (xy 370.84 229.87)
		)
		(stroke
			(width 0)
			(type default)
		)
	)
	(wire
		(pts
			(xy 138.43 133.35) (xy 140.97 133.35)
		)
		(stroke
			(width 0)
			(type default)
		)
	)
	(wire
		(pts
			(xy 224.79 207.01) (xy 224.79 215.9)
		)
		(stroke
			(width 0)
			(type default)
		)
	)
	(wire
		(pts
			(xy 320.04 66.04) (xy 325.12 66.04)
		)
		(stroke
			(width 0)
			(type default)
		)
	)
	(wire
		(pts
			(xy 224.79 200.66) (xy 224.79 201.93)
		)
		(stroke
			(width 0)
			(type default)
		)
	)
	(wire
		(pts
			(xy 257.81 83.82) (xy 257.81 86.36)
		)
		(stroke
			(width 0)
			(type default)
		)
	)
	(wire
		(pts
			(xy 134.62 251.46) (xy 134.62 252.73)
		)
		(stroke
			(width 0)
			(type default)
		)
	)
	(wire
		(pts
			(xy 227.33 90.17) (xy 227.33 88.9)
		)
		(stroke
			(width 0)
			(type default)
		)
	)
	(wire
		(pts
			(xy 285.75 154.94) (xy 293.37 154.94)
		)
		(stroke
			(width 0)
			(type default)
		)
	)
	(wire
		(pts
			(xy 241.3 157.48) (xy 241.3 158.75)
		)
		(stroke
			(width 0)
			(type default)
		)
	)
	(wire
		(pts
			(xy 233.68 147.32) (xy 257.81 147.32)
		)
		(stroke
			(width 0)
			(type default)
		)
	)
	(wire
		(pts
			(xy 284.48 229.87) (xy 284.48 236.22)
		)
		(stroke
			(width 0)
			(type default)
		)
	)
	(wire
		(pts
			(xy 132.08 55.88) (xy 118.11 55.88)
		)
		(stroke
			(width 0)
			(type default)
		)
	)
	(wire
		(pts
			(xy 350.52 53.34) (xy 350.52 57.15)
		)
		(stroke
			(width 0)
			(type default)
		)
	)
	(wire
		(pts
			(xy 375.92 105.41) (xy 379.73 105.41)
		)
		(stroke
			(width 0)
			(type default)
		)
	)
	(label "MOSI_SOFT"
		(at 299.72 142.24 180)
		(effects
			(font
				(size 1.27 1.27)
			)
			(justify right bottom)
		)
	)
	(label "SPI_CLK_SOFT"
		(at 299.72 144.78 180)
		(effects
			(font
				(size 1.27 1.27)
			)
			(justify right bottom)
		)
	)
	(label "SPI_DQ1_MISO"
		(at 212.09 53.34 0)
		(effects
			(font
				(size 1.27 1.27)
			)
			(justify left bottom)
		)
	)
	(label "SEL"
		(at 212.09 83.82 0)
		(effects
			(font
				(size 1.27 1.27)
			)
			(justify left bottom)
		)
	)
	(label "~{FLASH_CS_SOFT}"
		(at 312.42 149.86 180)
		(effects
			(font
				(size 1.27 1.27)
			)
			(justify right bottom)
		)
	)
	(label "DONE_SOFT"
		(at 312.42 154.94 180)
		(effects
			(font
				(size 1.27 1.27)
			)
			(justify right bottom)
		)
	)
	(label "INITN_SOFT"
		(at 381 236.22 180)
		(effects
			(font
				(size 1.27 1.27)
			)
			(justify right bottom)
		)
	)
	(label "DONE"
		(at 132.08 63.5 180)
		(effects
			(font
				(size 1.27 1.27)
			)
			(justify right bottom)
		)
	)
	(label "SPI_DQ3"
		(at 262.89 60.96 0)
		(effects
			(font
				(size 1.27 1.27)
			)
			(justify left bottom)
		)
	)
	(label "PROGRAMN"
		(at 209.55 215.9 0)
		(effects
			(font
				(size 1.27 1.27)
			)
			(justify left bottom)
		)
	)
	(label "MOSI_SOFT"
		(at 212.09 48.26 0)
		(effects
			(font
				(size 1.27 1.27)
			)
			(justify left bottom)
		)
	)
	(label "SPI_DQ1_MISO"
		(at 262.89 77.47 0)
		(effects
			(font
				(size 1.27 1.27)
			)
			(justify left bottom)
		)
	)
	(label "INITN"
		(at 350.52 229.87 0)
		(effects
			(font
				(size 1.27 1.27)
			)
			(justify left bottom)
		)
	)
	(label "SPI_DQ0_MOSI"
		(at 132.08 68.58 180)
		(effects
			(font
				(size 1.27 1.27)
			)
			(justify right bottom)
		)
	)
	(label "SPI_CLK"
		(at 262.89 82.55 0)
		(effects
			(font
				(size 1.27 1.27)
			)
			(justify left bottom)
		)
	)
	(label "SPI_DQ2"
		(at 132.08 73.66 180)
		(effects
			(font
				(size 1.27 1.27)
			)
			(justify right bottom)
		)
	)
	(label "SEL"
		(at 312.42 152.4 180)
		(effects
			(font
				(size 1.27 1.27)
			)
			(justify right bottom)
		)
	)
	(label "SPI_DQ0_MOSI"
		(at 262.89 72.39 0)
		(effects
			(font
				(size 1.27 1.27)
			)
			(justify left bottom)
		)
	)
	(label "~{FLASH_CS}"
		(at 132.08 66.04 180)
		(effects
			(font
				(size 1.27 1.27)
			)
			(justify right bottom)
		)
	)
	(label "INITN"
		(at 132.08 55.88 180)
		(effects
			(font
				(size 1.27 1.27)
			)
			(justify right bottom)
		)
	)
	(label "SPI_DQ2"
		(at 262.89 58.42 0)
		(effects
			(font
				(size 1.27 1.27)
			)
			(justify left bottom)
		)
	)
	(label "MISO_SOFT"
		(at 212.09 58.42 0)
		(effects
			(font
				(size 1.27 1.27)
			)
			(justify left bottom)
		)
	)
	(label "DONE_SOFT"
		(at 306.07 236.22 180)
		(effects
			(font
				(size 1.27 1.27)
			)
			(justify right bottom)
		)
	)
	(label "SPI_DQ3"
		(at 132.08 76.2 180)
		(effects
			(font
				(size 1.27 1.27)
			)
			(justify right bottom)
		)
	)
	(label "SPI_DQ0_MOSI"
		(at 212.09 43.18 0)
		(effects
			(font
				(size 1.27 1.27)
			)
			(justify left bottom)
		)
	)
	(label "SPI_CLK_SOFT"
		(at 212.09 68.58 0)
		(effects
			(font
				(size 1.27 1.27)
			)
			(justify left bottom)
		)
	)
	(label "SPI_CLK"
		(at 212.09 63.5 0)
		(effects
			(font
				(size 1.27 1.27)
			)
			(justify left bottom)
		)
	)
	(label "~{FLASH_CS}"
		(at 212.09 73.66 0)
		(effects
			(font
				(size 1.27 1.27)
			)
			(justify left bottom)
		)
	)
	(label "MISO_SOFT"
		(at 299.72 139.7 180)
		(effects
			(font
				(size 1.27 1.27)
			)
			(justify right bottom)
		)
	)
	(label "DONE"
		(at 278.13 229.87 0)
		(effects
			(font
				(size 1.27 1.27)
			)
			(justify left bottom)
		)
	)
	(label "SPI_DQ1_MISO"
		(at 132.08 71.12 180)
		(effects
			(font
				(size 1.27 1.27)
			)
			(justify right bottom)
		)
	)
	(label "SPI_CLK"
		(at 132.08 60.96 180)
		(effects
			(font
				(size 1.27 1.27)
			)
			(justify right bottom)
		)
	)
	(label "~{FLASH_CS}"
		(at 262.89 87.63 0)
		(effects
			(font
				(size 1.27 1.27)
			)
			(justify left bottom)
		)
	)
	(label "INITN_SOFT"
		(at 312.42 157.48 180)
		(effects
			(font
				(size 1.27 1.27)
			)
			(justify right bottom)
		)
	)
	(label "PROGRAMN"
		(at 132.08 58.42 180)
		(effects
			(font
				(size 1.27 1.27)
			)
			(justify right bottom)
		)
	)
	(label "~{FLASH_CS_SOFT}"
		(at 212.09 78.74 0)
		(effects
			(font
				(size 1.27 1.27)
			)
			(justify left bottom)
		)
	)
	(global_label "TMS"
		(shape input)
		(at 379.73 105.41 0)
		(fields_autoplaced yes)
		(effects
			(font
				(size 1.27 1.27)
			)
			(justify left)
		)
		(property "Intersheetrefs" "${INTERSHEET_REFS}"
			(at 385.7717 105.3306 0)
			(effects
				(font
					(size 1.27 1.27)
				)
				(justify left)
				(hide yes)
			)
		)
	)
	(global_label "TDO"
		(shape input)
		(at 379.73 115.57 0)
		(fields_autoplaced yes)
		(effects
			(font
				(size 1.27 1.27)
			)
			(justify left)
		)
		(property "Intersheetrefs" "${INTERSHEET_REFS}"
			(at 385.7112 115.4906 0)
			(effects
				(font
					(size 1.27 1.27)
				)
				(justify left)
				(hide yes)
			)
		)
	)
	(global_label "SCL"
		(shape input)
		(at 226.06 147.32 180)
		(fields_autoplaced yes)
		(effects
			(font
				(size 1.27 1.27)
			)
			(justify right)
		)
		(property "Intersheetrefs" "${INTERSHEET_REFS}"
			(at 220.1393 147.2406 0)
			(effects
				(font
					(size 1.27 1.27)
				)
				(justify right)
				(hide yes)
			)
		)
	)
	(global_label "JTAG_EN"
		(shape input)
		(at 379.73 125.73 0)
		(fields_autoplaced yes)
		(effects
			(font
				(size 1.27 1.27)
			)
			(justify left)
		)
		(property "Intersheetrefs" "${INTERSHEET_REFS}"
			(at 389.8841 125.6506 0)
			(effects
				(font
					(size 1.27 1.27)
				)
				(justify left)
				(hide yes)
			)
		)
	)
	(global_label "LED1"
		(shape input)
		(at 120.65 83.82 0)
		(fields_autoplaced yes)
		(effects
			(font
				(size 1.27 1.27)
			)
			(justify left)
		)
		(property "Intersheetrefs" "${INTERSHEET_REFS}"
			(at 127.7198 83.7406 0)
			(effects
				(font
					(size 1.27 1.27)
				)
				(justify left)
				(hide yes)
			)
		)
	)
	(global_label "TCK"
		(shape input)
		(at 379.73 110.49 0)
		(fields_autoplaced yes)
		(effects
			(font
				(size 1.27 1.27)
			)
			(justify left)
		)
		(property "Intersheetrefs" "${INTERSHEET_REFS}"
			(at 385.6507 110.4106 0)
			(effects
				(font
					(size 1.27 1.27)
				)
				(justify left)
				(hide yes)
			)
		)
	)
	(global_label "SDA"
		(shape input)
		(at 226.06 144.78 180)
		(fields_autoplaced yes)
		(effects
			(font
				(size 1.27 1.27)
			)
			(justify right)
		)
		(property "Intersheetrefs" "${INTERSHEET_REFS}"
			(at 220.0788 144.7006 0)
			(effects
				(font
					(size 1.27 1.27)
				)
				(justify right)
				(hide yes)
			)
		)
	)
	(global_label "LED0"
		(shape input)
		(at 120.65 81.28 0)
		(fields_autoplaced yes)
		(effects
			(font
				(size 1.27 1.27)
			)
			(justify left)
		)
		(property "Intersheetrefs" "${INTERSHEET_REFS}"
			(at 127.7198 81.2006 0)
			(effects
				(font
					(size 1.27 1.27)
				)
				(justify left)
				(hide yes)
			)
		)
	)
	(global_label "40MHz_3V3"
		(shape input)
		(at 168.91 257.81 0)
		(fields_autoplaced yes)
		(effects
			(font
				(size 1.27 1.27)
			)
			(justify left)
		)
		(property "Intersheetrefs" "${INTERSHEET_REFS}"
			(at 182.0274 257.7306 0)
			(effects
				(font
					(size 1.27 1.27)
				)
				(justify left)
				(hide yes)
			)
		)
	)
	(global_label "TDI"
		(shape input)
		(at 379.73 120.65 0)
		(fields_autoplaced yes)
		(effects
			(font
				(size 1.27 1.27)
			)
			(justify left)
		)
		(property "Intersheetrefs" "${INTERSHEET_REFS}"
			(at 384.9855 120.5706 0)
			(effects
				(font
					(size 1.27 1.27)
				)
				(justify left)
				(hide yes)
			)
		)
	)
	(symbol
		(lib_id "antmicroCapacitors0402:C_100n_0402")
		(at 350.52 62.23 90)
		(unit 1)
		(exclude_from_sim no)
		(in_bom yes)
		(on_board yes)
		(dnp no)
		(fields_autoplaced yes)
		(property "Reference" "C82"
			(at 353.06 58.4135 90)
			(effects
				(font
					(size 1.27 1.27)
					(thickness 0.15)
				)
				(justify right)
			)
		)
		(property "Value" "C_100n_0402"
			(at 360.68 41.91 0)
			(effects
				(font
					(size 1.27 1.27)
					(thickness 0.15)
				)
				(justify left bottom)
				(hide yes)
			)
		)
		(property "Footprint" "antmicro-footprints:C_0402_1005Metric"
			(at 363.22 41.91 0)
			(effects
				(font
					(size 1.27 1.27)
					(thickness 0.15)
				)
				(justify left bottom)
				(hide yes)
			)
		)
		(property "Datasheet" "https://www.murata.com/products/productdetail?partno=GRM155R61H104KE14%23"
			(at 365.76 41.91 0)
			(effects
				(font
					(size 1.27 1.27)
					(thickness 0.15)
				)
				(justify left bottom)
				(hide yes)
			)
		)
		(property "Description" "SMD Multilayer Ceramic Capacitor, 0.1 µF, 50 V, 0402 [1005 Metric], ± 10%, X5R, GRM Series"
			(at 350.52 62.23 0)
			(effects
				(font
					(size 1.27 1.27)
				)
				(hide yes)
			)
		)
		(property "Manufacturer" "Murata"
			(at 370.84 41.91 0)
			(effects
				(font
					(size 1.27 1.27)
					(thickness 0.15)
				)
				(justify left bottom)
				(hide yes)
			)
		)
		(property "MPN" "GRM155R61H104KE14D"
			(at 368.3 41.91 0)
			(effects
				(font
					(size 1.27 1.27)
					(thickness 0.15)
				)
				(justify left bottom)
				(hide yes)
			)
		)
		(property "Val" "100n"
			(at 353.06 60.9535 90)
			(effects
				(font
					(size 1.27 1.27)
					(thickness 0.15)
				)
				(justify right)
			)
		)
		(property "License" "Apache-2.0"
			(at 373.38 41.91 0)
			(effects
				(font
					(size 1.27 1.27)
					(thickness 0.15)
				)
				(justify left bottom)
				(hide yes)
			)
		)
		(property "Author" "Antmicro"
			(at 375.92 41.91 0)
			(effects
				(font
					(size 1.27 1.27)
					(thickness 0.15)
				)
				(justify left bottom)
				(hide yes)
			)
		)
		(property "Voltage" "50V"
			(at 378.46 41.91 0)
			(effects
				(font
					(size 1.27 1.27)
				)
				(justify left bottom)
				(hide yes)
			)
		)
		(property "Dielectric" "X5R"
			(at 381 41.91 0)
			(effects
				(font
					(size 1.27 1.27)
				)
				(justify left bottom)
				(hide yes)
			)
		)
		(pin "1"
		)
		(pin "2"
		)
		(instances
			(project "sdi-mipi-video-converter"
				(path ""
					(reference "C82")
					(unit 1)
				)
			)
		)
	)
	(symbol
		(lib_id "antmicroResistors0402:R_4k7_0402")
		(at 309.88 41.91 270)
		(unit 1)
		(exclude_from_sim no)
		(in_bom yes)
		(on_board yes)
		(dnp no)
		(property "Reference" "R83"
			(at 311.15 43.18 90)
			(effects
				(font
					(size 1.27 1.27)
					(thickness 0.15)
				)
				(justify left)
			)
		)
		(property "Value" "R_4k7_0402"
			(at 297.18 62.23 0)
			(effects
				(font
					(size 1.27 1.27)
					(thickness 0.15)
				)
				(justify left bottom)
				(hide yes)
			)
		)
		(property "Footprint" "antmicro-footprints:R_0402_1005Metric"
			(at 294.64 62.23 0)
			(effects
				(font
					(size 1.27 1.27)
					(thickness 0.15)
				)
				(justify left bottom)
				(hide yes)
			)
		)
		(property "Datasheet" "https://www.bourns.com/docs/product-datasheets/cr.pdf"
			(at 292.1 62.23 0)
			(effects
				(font
					(size 1.27 1.27)
					(thickness 0.15)
				)
				(justify left bottom)
				(hide yes)
			)
		)
		(property "Description" "SMD Chip Resistor, 4.7 kohm, ± 1%, 62.5 mW, 0402 [1005 Metric], Thick Film, General Purpose"
			(at 309.88 41.91 0)
			(effects
				(font
					(size 1.27 1.27)
				)
				(hide yes)
			)
		)
		(property "Manufacturer" "Bourns"
			(at 287.02 62.23 0)
			(effects
				(font
					(size 1.27 1.27)
					(thickness 0.15)
				)
				(justify left bottom)
				(hide yes)
			)
		)
		(property "MPN" "CR0402-FX-4701GLF"
			(at 289.56 62.23 0)
			(effects
				(font
					(size 1.27 1.27)
					(thickness 0.15)
				)
				(justify left bottom)
				(hide yes)
			)
		)
		(property "Val" "4k7"
			(at 311.15 45.72 90)
			(effects
				(font
					(size 1.27 1.27)
					(thickness 0.15)
				)
				(justify left)
			)
		)
		(property "License" "Apache-2.0"
			(at 284.48 62.23 0)
			(effects
				(font
					(size 1.27 1.27)
					(thickness 0.15)
				)
				(justify left bottom)
				(hide yes)
			)
		)
		(property "Author" "Antmicro"
			(at 281.94 62.23 0)
			(effects
				(font
					(size 1.27 1.27)
					(thickness 0.15)
				)
				(justify left bottom)
				(hide yes)
			)
		)
		(property "Tolerance" "1%"
			(at 299.72 62.23 0)
			(effects
				(font
					(size 1.27 1.27)
				)
				(justify left bottom)
				(hide yes)
			)
		)
		(pin "1"
		)
		(pin "2"
		)
		(instances
			(project "sdi-mipi-video-converter"
				(path ""
					(reference "R83")
					(unit 1)
				)
			)
		)
	)
	(symbol
		(lib_id "antmicropower:+3.3V")
		(at 361.95 201.93 0)
		(unit 1)
		(exclude_from_sim no)
		(in_bom yes)
		(on_board yes)
		(dnp no)
		(fields_autoplaced yes)
		(property "Reference" "#PWR0184"
			(at 361.95 205.74 0)
			(effects
				(font
					(size 1.27 1.27)
				)
				(hide yes)
			)
		)
		(property "Value" "+3V3"
			(at 361.95 196.85 0)
			(effects
				(font
					(size 1.27 1.27)
				)
			)
		)
		(property "Footprint" ""
			(at 361.95 201.93 0)
			(effects
				(font
					(size 1.27 1.27)
				)
				(hide yes)
			)
		)
		(property "Datasheet" ""
			(at 361.95 201.93 0)
			(effects
				(font
					(size 1.27 1.27)
				)
				(hide yes)
			)
		)
		(property "Description" ""
			(at 361.95 201.93 0)
			(effects
				(font
					(size 1.27 1.27)
				)
				(hide yes)
			)
		)
		(pin "1"
		)
		(instances
			(project "sdi-mipi-video-converter"
				(path ""
					(reference "#PWR0184")
					(unit 1)
				)
			)
		)
	)
	(symbol
		(lib_id "antmicropower:GND")
		(at 350.52 68.58 0)
		(unit 1)
		(exclude_from_sim no)
		(in_bom yes)
		(on_board yes)
		(dnp no)
		(fields_autoplaced yes)
		(property "Reference" "#PWR0180"
			(at 359.41 71.12 0)
			(effects
				(font
					(size 1.27 1.27)
					(thickness 0.15)
				)
				(justify left bottom)
				(hide yes)
			)
		)
		(property "Value" "GND"
			(at 350.52 73.025 0)
			(effects
				(font
					(size 1.27 1.27)
					(thickness 0.15)
				)
			)
		)
		(property "Footprint" ""
			(at 359.41 76.2 0)
			(effects
				(font
					(size 1.27 1.27)
					(thickness 0.15)
				)
				(justify left bottom)
				(hide yes)
			)
		)
		(property "Datasheet" ""
			(at 359.41 81.28 0)
			(effects
				(font
					(size 1.27 1.27)
					(thickness 0.15)
				)
				(justify left bottom)
				(hide yes)
			)
		)
		(property "Description" ""
			(at 350.52 68.58 0)
			(effects
				(font
					(size 1.27 1.27)
				)
				(hide yes)
			)
		)
		(property "Author" "Antmicro"
			(at 359.41 76.2 0)
			(effects
				(font
					(size 1.27 1.27)
					(thickness 0.15)
				)
				(justify left bottom)
				(hide yes)
			)
		)
		(property "License" "Apache-2.0"
			(at 359.41 78.74 0)
			(effects
				(font
					(size 1.27 1.27)
					(thickness 0.15)
				)
				(justify left bottom)
				(hide yes)
			)
		)
		(pin "1"
		)
		(instances
			(project "sdi-mipi-video-converter"
				(path ""
					(reference "#PWR0180")
					(unit 1)
				)
			)
		)
	)
	(symbol
		(lib_id "antmicroLogicSignalSwitchesMultiplexersDecoders:TMUX1574RSVR")
		(at 251.46 45.72 0)
		(mirror y)
		(unit 1)
		(exclude_from_sim no)
		(in_bom yes)
		(on_board yes)
		(dnp no)
		(fields_autoplaced yes)
		(property "Reference" "U21"
			(at 240.03 35.56 0)
			(effects
				(font
					(size 1.27 1.27)
				)
			)
		)
		(property "Value" "TMUX1574RSVR"
			(at 240.03 38.1 0)
			(effects
				(font
					(size 1.27 1.27)
				)
			)
		)
		(property "Footprint" "antmicro-footprints:UQFN-16-1.8x2.6mm_P0.4mm_Texas_RSV0016A"
			(at 207.01 50.8 0)
			(effects
				(font
					(size 1.27 1.27)
				)
				(justify left bottom)
				(hide yes)
			)
		)
		(property "Datasheet" "https://www.ti.com/lit/ds/symlink/tmux1574.pdf?ts=1672927977241&ref_url=https%253A%252F%252Fwww.ti.com%252Fproduct%252FTMUX1574%253FHQS%253DTI-null-null-octopart-df-pf-xrefTI-wwe"
			(at 207.01 53.34 0)
			(effects
				(font
					(size 1.27 1.27)
				)
				(justify left bottom)
				(hide yes)
			)
		)
		(property "Description" "Analogue switch"
			(at 251.46 45.72 0)
			(effects
				(font
					(size 1.27 1.27)
				)
				(hide yes)
			)
		)
		(property "MPN" "TMUX1574RSVR"
			(at 207.01 55.88 0)
			(effects
				(font
					(size 1.27 1.27)
				)
				(justify left bottom)
				(hide yes)
			)
		)
		(property "Manufacturer" "Texas Instruments"
			(at 207.01 58.42 0)
			(effects
				(font
					(size 1.27 1.27)
				)
				(justify left bottom)
				(hide yes)
			)
		)
		(property "License" "Apache-2.0"
			(at 207.01 63.5 0)
			(effects
				(font
					(size 1.27 1.27)
				)
				(justify left bottom)
				(hide yes)
			)
		)
		(property "Author" "Antmicro"
			(at 207.01 60.96 0)
			(effects
				(font
					(size 1.27 1.27)
				)
				(justify left bottom)
				(hide yes)
			)
		)
		(pin "1"
		)
		(pin "10"
		)
		(pin "11"
		)
		(pin "12"
		)
		(pin "13"
		)
		(pin "14"
		)
		(pin "15"
		)
		(pin "16"
		)
		(pin "2"
		)
		(pin "3"
		)
		(pin "4"
		)
		(pin "5"
		)
		(pin "6"
		)
		(pin "7"
		)
		(pin "8"
		)
		(pin "9"
		)
		(instances
			(project "sdi-mipi-video-converter"
				(path ""
					(reference "U21")
					(unit 1)
				)
			)
		)
	)
	(symbol
		(lib_id "antmicroResistors0402:R_0R_0402")
		(at 288.29 236.22 0)
		(unit 1)
		(exclude_from_sim no)
		(in_bom yes)
		(on_board yes)
		(dnp no)
		(fields_autoplaced yes)
		(property "Reference" "R77"
			(at 290.83 240.03 0)
			(effects
				(font
					(size 1.27 1.27)
					(thickness 0.15)
				)
			)
		)
		(property "Value" "R_0R_0402"
			(at 308.61 248.92 0)
			(effects
				(font
					(size 1.27 1.27)
					(thickness 0.15)
				)
				(justify left bottom)
				(hide yes)
			)
		)
		(property "Footprint" "antmicro-footprints:R_0402_1005Metric"
			(at 308.61 251.46 0)
			(effects
				(font
					(size 1.27 1.27)
					(thickness 0.15)
				)
				(justify left bottom)
				(hide yes)
			)
		)
		(property "Datasheet" "https://industrial.panasonic.com/cdbs/www-data/pdf/RDA0000/AOA0000C301.pdf"
			(at 308.61 254 0)
			(effects
				(font
					(size 1.27 1.27)
					(thickness 0.15)
				)
				(justify left bottom)
				(hide yes)
			)
		)
		(property "Description" "SMD Chip Resistor, Jumper, 0 ohm, 100 mW, 0402 [1005 Metric], Thick Film, General Purpose"
			(at 288.29 236.22 0)
			(effects
				(font
					(size 1.27 1.27)
				)
				(hide yes)
			)
		)
		(property "Manufacturer" "Panasonic"
			(at 308.61 259.08 0)
			(effects
				(font
					(size 1.27 1.27)
					(thickness 0.15)
				)
				(justify left bottom)
				(hide yes)
			)
		)
		(property "MPN" "ERJ2GE0R00X"
			(at 308.61 256.54 0)
			(effects
				(font
					(size 1.27 1.27)
					(thickness 0.15)
				)
				(justify left bottom)
				(hide yes)
			)
		)
		(property "Val" "0R"
			(at 290.83 242.57 0)
			(effects
				(font
					(size 1.27 1.27)
					(thickness 0.15)
				)
			)
		)
		(property "License" "Apache-2.0"
			(at 308.61 261.62 0)
			(effects
				(font
					(size 1.27 1.27)
					(thickness 0.15)
				)
				(justify left bottom)
				(hide yes)
			)
		)
		(property "Author" "Antmicro"
			(at 308.61 264.16 0)
			(effects
				(font
					(size 1.27 1.27)
					(thickness 0.15)
				)
				(justify left bottom)
				(hide yes)
			)
		)
		(property "Tolerance" "~"
			(at 308.61 246.38 0)
			(effects
				(font
					(size 1.27 1.27)
				)
				(justify left bottom)
				(hide yes)
			)
		)
		(property "Current" "1A"
			(at 308.61 266.7 0)
			(effects
				(font
					(size 1.27 1.27)
					(thickness 0.15)
				)
				(justify left bottom)
				(hide yes)
			)
		)
		(pin "1"
		)
		(pin "2"
		)
		(instances
			(project "sdi-mipi-video-converter"
				(path ""
					(reference "R77")
					(unit 1)
				)
			)
		)
	)
	(symbol
		(lib_id "antmicropower:GND")
		(at 241.3 165.1 0)
		(mirror y)
		(unit 1)
		(exclude_from_sim no)
		(in_bom yes)
		(on_board yes)
		(dnp no)
		(fields_autoplaced yes)
		(property "Reference" "#PWR0174"
			(at 232.41 167.64 0)
			(effects
				(font
					(size 1.27 1.27)
					(thickness 0.15)
				)
				(justify left bottom)
				(hide yes)
			)
		)
		(property "Value" "GND"
			(at 241.3 170.18 0)
			(effects
				(font
					(size 1.27 1.27)
					(thickness 0.15)
				)
			)
		)
		(property "Footprint" ""
			(at 232.41 172.72 0)
			(effects
				(font
					(size 1.27 1.27)
					(thickness 0.15)
				)
				(justify left bottom)
				(hide yes)
			)
		)
		(property "Datasheet" ""
			(at 232.41 177.8 0)
			(effects
				(font
					(size 1.27 1.27)
					(thickness 0.15)
				)
				(justify left bottom)
				(hide yes)
			)
		)
		(property "Description" ""
			(at 241.3 165.1 0)
			(effects
				(font
					(size 1.27 1.27)
				)
				(hide yes)
			)
		)
		(property "Author" "Antmicro"
			(at 232.41 172.72 0)
			(effects
				(font
					(size 1.27 1.27)
					(thickness 0.15)
				)
				(justify left bottom)
				(hide yes)
			)
		)
		(property "License" "Apache-2.0"
			(at 232.41 175.26 0)
			(effects
				(font
					(size 1.27 1.27)
					(thickness 0.15)
				)
				(justify left bottom)
				(hide yes)
			)
		)
		(pin "1"
		)
		(instances
			(project "sdi-mipi-video-converter"
				(path ""
					(reference "#PWR0174")
					(unit 1)
				)
			)
		)
	)
	(symbol
		(lib_id "antmicroFPGAChips:CrossLink_LIFCL-40-9BG256C")
		(at 88.9 130.81 0)
		(mirror y)
		(unit 11)
		(exclude_from_sim no)
		(in_bom yes)
		(on_board yes)
		(dnp no)
		(fields_autoplaced yes)
		(property "Reference" "U11"
			(at 74.295 120.65 0)
			(effects
				(font
					(size 1.27 1.27)
					(thickness 0.15)
				)
			)
		)
		(property "Value" "LIFCL-40-9BG256C"
			(at 74.295 123.19 0)
			(effects
				(font
					(size 1.27 1.27)
					(thickness 0.15)
				)
				(hide yes)
			)
		)
		(property "Footprint" "antmicro-footprints:BGA-256_14x14mm_Layout16x16_P0.8mm"
			(at 35.56 138.43 0)
			(effects
				(font
					(size 1.27 1.27)
					(thickness 0.15)
				)
				(justify left bottom)
				(hide yes)
			)
		)
		(property "Datasheet" "https://www.latticesemi.com/-/media/LatticeSemi/Documents/DataSheets/CrossLink/FPGA-DS-02007-2-1-CrossLink-Family-Data-Sheet.ashx?document_id=51662"
			(at 35.56 140.97 0)
			(effects
				(font
					(size 1.27 1.27)
					(thickness 0.15)
				)
				(justify left bottom)
				(hide yes)
			)
		)
		(property "Description" "CrossLink-NX™ Field Programmable Gate Array 256-LFBGA"
			(at 74.295 123.19 0)
			(effects
				(font
					(size 1.27 1.27)
				)
				(hide yes)
			)
		)
		(property "MPN" "LIFCL-40-9BG256C"
			(at 74.295 125.73 0)
			(effects
				(font
					(size 1.27 1.27)
					(thickness 0.15)
				)
			)
		)
		(property "Manufacturer" "Lattice Semiconductor"
			(at 35.56 143.51 0)
			(effects
				(font
					(size 1.27 1.27)
					(thickness 0.15)
				)
				(justify left bottom)
				(hide yes)
			)
		)
		(property "Author" "Antmicro"
			(at 35.56 146.05 0)
			(effects
				(font
					(size 1.27 1.27)
					(thickness 0.15)
				)
				(justify left bottom)
				(hide yes)
			)
		)
		(property "License" "Apache-2.0"
			(at 35.56 148.59 0)
			(effects
				(font
					(size 1.27 1.27)
					(thickness 0.15)
				)
				(justify left bottom)
				(hide yes)
			)
		)
		(pin "B16"
		)
		(pin "C12"
		)
		(pin "C13"
		)
		(pin "C14"
		)
		(pin "C15"
		)
		(pin "C16"
		)
		(pin "D11"
		)
		(pin "D12"
		)
		(pin "D13"
		)
		(pin "D15"
		)
		(pin "D16"
		)
		(pin "E15"
		)
		(pin "E16"
		)
		(pin "D10"
		)
		(pin "E10"
		)
		(pin "E11"
		)
		(pin "E12"
		)
		(pin "E13"
		)
		(pin "E14"
		)
		(pin "E9"
		)
		(pin "F10"
		)
		(pin "F11"
		)
		(pin "F13"
		)
		(pin "F14"
		)
		(pin "F15"
		)
		(pin "F16"
		)
		(pin "F9"
		)
		(pin "G10"
		)
		(pin "G11"
		)
		(pin "G12"
		)
		(pin "G13"
		)
		(pin "G14"
		)
		(pin "G15"
		)
		(pin "G16"
		)
		(pin "G9"
		)
		(pin "H10"
		)
		(pin "H11"
		)
		(pin "H12"
		)
		(pin "H13"
		)
		(pin "H14"
		)
		(pin "H15"
		)
		(pin "H16"
		)
		(pin "J11"
		)
		(pin "J12"
		)
		(pin "J13"
		)
		(pin "J15"
		)
		(pin "J16"
		)
		(pin "K11"
		)
		(pin "K12"
		)
		(pin "L10"
		)
		(pin "L11"
		)
		(pin "L12"
		)
		(pin "M11"
		)
		(pin "M12"
		)
		(pin "M13"
		)
		(pin "M14"
		)
		(pin "M15"
		)
		(pin "M16"
		)
		(pin "N11"
		)
		(pin "N12"
		)
		(pin "N13"
		)
		(pin "N14"
		)
		(pin "N15"
		)
		(pin "N16"
		)
		(pin "P10"
		)
		(pin "P11"
		)
		(pin "P12"
		)
		(pin "P14"
		)
		(pin "P15"
		)
		(pin "P16"
		)
		(pin "R10"
		)
		(pin "R11"
		)
		(pin "R12"
		)
		(pin "R13"
		)
		(pin "R14"
		)
		(pin "R15"
		)
		(pin "R16"
		)
		(pin "T11"
		)
		(pin "T12"
		)
		(pin "T13"
		)
		(pin "T14"
		)
		(pin "T15"
		)
		(pin "L8"
		)
		(pin "L9"
		)
		(pin "M10"
		)
		(pin "M8"
		)
		(pin "M9"
		)
		(pin "N10"
		)
		(pin "N6"
		)
		(pin "N8"
		)
		(pin "N9"
		)
		(pin "P4"
		)
		(pin "P5"
		)
		(pin "P6"
		)
		(pin "P7"
		)
		(pin "P8"
		)
		(pin "P9"
		)
		(pin "R1"
		)
		(pin "R2"
		)
		(pin "R3"
		)
		(pin "R4"
		)
		(pin "R5"
		)
		(pin "R6"
		)
		(pin "R7"
		)
		(pin "R8"
		)
		(pin "R9"
		)
		(pin "T10"
		)
		(pin "T2"
		)
		(pin "T3"
		)
		(pin "T4"
		)
		(pin "T5"
		)
		(pin "T6"
		)
		(pin "T7"
		)
		(pin "T8"
		)
		(pin "T9"
		)
		(pin "K7"
		)
		(pin "L6"
		)
		(pin "L7"
		)
		(pin "M4"
		)
		(pin "M7"
		)
		(pin "N3"
		)
		(pin "N4"
		)
		(pin "N5"
		)
		(pin "P1"
		)
		(pin "P2"
		)
		(pin "P3"
		)
		(pin "H1"
		)
		(pin "H2"
		)
		(pin "H3"
		)
		(pin "H4"
		)
		(pin "H5"
		)
		(pin "H6"
		)
		(pin "J1"
		)
		(pin "J2"
		)
		(pin "J4"
		)
		(pin "J5"
		)
		(pin "J6"
		)
		(pin "K1"
		)
		(pin "K2"
		)
		(pin "K3"
		)
		(pin "K4"
		)
		(pin "K5"
		)
		(pin "K6"
		)
		(pin "L1"
		)
		(pin "L2"
		)
		(pin "L3"
		)
		(pin "L4"
		)
		(pin "L5"
		)
		(pin "M1"
		)
		(pin "M2"
		)
		(pin "M3"
		)
		(pin "N1"
		)
		(pin "N2"
		)
		(pin "D4"
		)
		(pin "D5"
		)
		(pin "D6"
		)
		(pin "E4"
		)
		(pin "E5"
		)
		(pin "E6"
		)
		(pin "F4"
		)
		(pin "F5"
		)
		(pin "F6"
		)
		(pin "G3"
		)
		(pin "G4"
		)
		(pin "G6"
		)
		(pin "B1"
		)
		(pin "B2"
		)
		(pin "C1"
		)
		(pin "C2"
		)
		(pin "D1"
		)
		(pin "D2"
		)
		(pin "E1"
		)
		(pin "E2"
		)
		(pin "F1"
		)
		(pin "F2"
		)
		(pin "A3"
		)
		(pin "A4"
		)
		(pin "A5"
		)
		(pin "A6"
		)
		(pin "A7"
		)
		(pin "B3"
		)
		(pin "B4"
		)
		(pin "B5"
		)
		(pin "B6"
		)
		(pin "B7"
		)
		(pin "K13"
		)
		(pin "K14"
		)
		(pin "K15"
		)
		(pin "K16"
		)
		(pin "L13"
		)
		(pin "L14"
		)
		(pin "L15"
		)
		(pin "L16"
		)
		(pin "A11"
		)
		(pin "A12"
		)
		(pin "A14"
		)
		(pin "A15"
		)
		(pin "A9"
		)
		(pin "B12"
		)
		(pin "B9"
		)
		(pin "C11"
		)
		(pin "A1"
		)
		(pin "A10"
		)
		(pin "A13"
		)
		(pin "A16"
		)
		(pin "A2"
		)
		(pin "A8"
		)
		(pin "B10"
		)
		(pin "B11"
		)
		(pin "B13"
		)
		(pin "B14"
		)
		(pin "B15"
		)
		(pin "B8"
		)
		(pin "C10"
		)
		(pin "C3"
		)
		(pin "C4"
		)
		(pin "C5"
		)
		(pin "C6"
		)
		(pin "C7"
		)
		(pin "C8"
		)
		(pin "C9"
		)
		(pin "D14"
		)
		(pin "D3"
		)
		(pin "D7"
		)
		(pin "D8"
		)
		(pin "D9"
		)
		(pin "E3"
		)
		(pin "E7"
		)
		(pin "E8"
		)
		(pin "F12"
		)
		(pin "F3"
		)
		(pin "F7"
		)
		(pin "F8"
		)
		(pin "G1"
		)
		(pin "G2"
		)
		(pin "G5"
		)
		(pin "G7"
		)
		(pin "G8"
		)
		(pin "H7"
		)
		(pin "H8"
		)
		(pin "H9"
		)
		(pin "J10"
		)
		(pin "J14"
		)
		(pin "J3"
		)
		(pin "J7"
		)
		(pin "J8"
		)
		(pin "J9"
		)
		(pin "K10"
		)
		(pin "K8"
		)
		(pin "K9"
		)
		(pin "M5"
		)
		(pin "M6"
		)
		(pin "N7"
		)
		(pin "P13"
		)
		(pin "T1"
		)
		(pin "T16"
		)
		(instances
			(project "sdi-mipi-video-converter"
				(path ""
					(reference "U11")
					(unit 11)
				)
			)
		)
	)
	(symbol
		(lib_id "antmicroResistors0402:R_100R_0402")
		(at 227.33 226.06 0)
		(unit 1)
		(exclude_from_sim no)
		(in_bom yes)
		(on_board yes)
		(dnp no)
		(fields_autoplaced yes)
		(property "Reference" "R70"
			(at 229.87 219.71 0)
			(effects
				(font
					(size 1.27 1.27)
					(thickness 0.15)
				)
			)
		)
		(property "Value" "R_100R_0402"
			(at 247.65 238.76 0)
			(effects
				(font
					(size 1.27 1.27)
					(thickness 0.15)
				)
				(justify left bottom)
				(hide yes)
			)
		)
		(property "Footprint" "antmicro-footprints:R_0402_1005Metric"
			(at 247.65 241.3 0)
			(effects
				(font
					(size 1.27 1.27)
					(thickness 0.15)
				)
				(justify left bottom)
				(hide yes)
			)
		)
		(property "Datasheet" "https://www.bourns.com/docs/product-datasheets/cr.pdf"
			(at 247.65 243.84 0)
			(effects
				(font
					(size 1.27 1.27)
					(thickness 0.15)
				)
				(justify left bottom)
				(hide yes)
			)
		)
		(property "Description" "SMD Chip Resistor, 100 ohm, ± 1%, 62.5 mW, 0402 [1005 Metric], Thick Film, General Purpose"
			(at 227.33 226.06 0)
			(effects
				(font
					(size 1.27 1.27)
				)
				(hide yes)
			)
		)
		(property "Manufacturer" "Bourns"
			(at 247.65 248.92 0)
			(effects
				(font
					(size 1.27 1.27)
					(thickness 0.15)
				)
				(justify left bottom)
				(hide yes)
			)
		)
		(property "MPN" "CR0402-FX-1000GLF"
			(at 247.65 246.38 0)
			(effects
				(font
					(size 1.27 1.27)
					(thickness 0.15)
				)
				(justify left bottom)
				(hide yes)
			)
		)
		(property "Val" "100R"
			(at 229.87 222.25 0)
			(effects
				(font
					(size 1.27 1.27)
					(thickness 0.15)
				)
			)
		)
		(property "License" "Apache-2.0"
			(at 247.65 251.46 0)
			(effects
				(font
					(size 1.27 1.27)
					(thickness 0.15)
				)
				(justify left bottom)
				(hide yes)
			)
		)
		(property "Author" "Antmicro"
			(at 247.65 254 0)
			(effects
				(font
					(size 1.27 1.27)
					(thickness 0.15)
				)
				(justify left bottom)
				(hide yes)
			)
		)
		(property "Tolerance" "1%"
			(at 247.65 236.22 0)
			(effects
				(font
					(size 1.27 1.27)
				)
				(justify left bottom)
				(hide yes)
			)
		)
		(pin "1"
		)
		(pin "2"
		)
		(instances
			(project "sdi-mipi-video-converter"
				(path ""
					(reference "R70")
					(unit 1)
				)
			)
		)
	)
	(symbol
		(lib_id "antmicroResistors0402:R_0R_0402")
		(at 226.06 158.75 90)
		(mirror x)
		(unit 1)
		(exclude_from_sim no)
		(in_bom yes)
		(on_board yes)
		(dnp no)
		(property "Reference" "R85"
			(at 227.33 160.02 90)
			(effects
				(font
					(size 1.27 1.27)
					(thickness 0.15)
				)
				(justify right)
			)
		)
		(property "Value" "R_0R_0402"
			(at 238.76 179.07 0)
			(effects
				(font
					(size 1.27 1.27)
					(thickness 0.15)
				)
				(justify left bottom)
				(hide yes)
			)
		)
		(property "Footprint" "antmicro-footprints:R_0402_1005Metric"
			(at 241.3 179.07 0)
			(effects
				(font
					(size 1.27 1.27)
					(thickness 0.15)
				)
				(justify left bottom)
				(hide yes)
			)
		)
		(property "Datasheet" "https://industrial.panasonic.com/cdbs/www-data/pdf/RDA0000/AOA0000C301.pdf"
			(at 243.84 179.07 0)
			(effects
				(font
					(size 1.27 1.27)
					(thickness 0.15)
				)
				(justify left bottom)
				(hide yes)
			)
		)
		(property "Description" "SMD Chip Resistor, Jumper, 0 ohm, 100 mW, 0402 [1005 Metric], Thick Film, General Purpose"
			(at 226.06 158.75 0)
			(effects
				(font
					(size 1.27 1.27)
				)
				(hide yes)
			)
		)
		(property "Manufacturer" "Panasonic"
			(at 248.92 179.07 0)
			(effects
				(font
					(size 1.27 1.27)
					(thickness 0.15)
				)
				(justify left bottom)
				(hide yes)
			)
		)
		(property "MPN" "ERJ2GE0R00X"
			(at 246.38 179.07 0)
			(effects
				(font
					(size 1.27 1.27)
					(thickness 0.15)
				)
				(justify left bottom)
				(hide yes)
			)
		)
		(property "Val" "0R"
			(at 227.33 162.56 90)
			(effects
				(font
					(size 1.27 1.27)
					(thickness 0.15)
				)
				(justify right)
			)
		)
		(property "License" "Apache-2.0"
			(at 251.46 179.07 0)
			(effects
				(font
					(size 1.27 1.27)
					(thickness 0.15)
				)
				(justify left bottom)
				(hide yes)
			)
		)
		(property "Author" "Antmicro"
			(at 254 179.07 0)
			(effects
				(font
					(size 1.27 1.27)
					(thickness 0.15)
				)
				(justify left bottom)
				(hide yes)
			)
		)
		(property "Tolerance" "~"
			(at 236.22 179.07 0)
			(effects
				(font
					(size 1.27 1.27)
				)
				(justify left bottom)
				(hide yes)
			)
		)
		(property "Current" "1A"
			(at 256.54 179.07 0)
			(effects
				(font
					(size 1.27 1.27)
					(thickness 0.15)
				)
				(justify left bottom)
				(hide yes)
			)
		)
		(pin "1"
		)
		(pin "2"
		)
		(instances
			(project "sdi-mipi-video-converter"
				(path ""
					(reference "R85")
					(unit 1)
				)
			)
		)
	)
	(symbol
		(lib_id "antmicropower:+3.3V")
		(at 224.79 200.66 0)
		(unit 1)
		(exclude_from_sim no)
		(in_bom yes)
		(on_board yes)
		(dnp no)
		(fields_autoplaced yes)
		(property "Reference" "#PWR0166"
			(at 224.79 204.47 0)
			(effects
				(font
					(size 1.27 1.27)
				)
				(hide yes)
			)
		)
		(property "Value" "+3V3"
			(at 224.79 195.58 0)
			(effects
				(font
					(size 1.27 1.27)
				)
			)
		)
		(property "Footprint" ""
			(at 224.79 200.66 0)
			(effects
				(font
					(size 1.27 1.27)
				)
				(hide yes)
			)
		)
		(property "Datasheet" ""
			(at 224.79 200.66 0)
			(effects
				(font
					(size 1.27 1.27)
				)
				(hide yes)
			)
		)
		(property "Description" ""
			(at 224.79 200.66 0)
			(effects
				(font
					(size 1.27 1.27)
				)
				(hide yes)
			)
		)
		(pin "1"
		)
		(instances
			(project "sdi-mipi-video-converter"
				(path ""
					(reference "#PWR0166")
					(unit 1)
				)
			)
		)
	)
	(symbol
		(lib_id "antmicroResistors0402:R_100R_0402")
		(at 237.49 226.06 0)
		(unit 1)
		(exclude_from_sim no)
		(in_bom yes)
		(on_board yes)
		(dnp no)
		(fields_autoplaced yes)
		(property "Reference" "R72"
			(at 240.03 219.71 0)
			(effects
				(font
					(size 1.27 1.27)
					(thickness 0.15)
				)
			)
		)
		(property "Value" "R_100R_0402"
			(at 257.81 238.76 0)
			(effects
				(font
					(size 1.27 1.27)
					(thickness 0.15)
				)
				(justify left bottom)
				(hide yes)
			)
		)
		(property "Footprint" "antmicro-footprints:R_0402_1005Metric"
			(at 257.81 241.3 0)
			(effects
				(font
					(size 1.27 1.27)
					(thickness 0.15)
				)
				(justify left bottom)
				(hide yes)
			)
		)
		(property "Datasheet" "https://www.bourns.com/docs/product-datasheets/cr.pdf"
			(at 257.81 243.84 0)
			(effects
				(font
					(size 1.27 1.27)
					(thickness 0.15)
				)
				(justify left bottom)
				(hide yes)
			)
		)
		(property "Description" "SMD Chip Resistor, 100 ohm, ± 1%, 62.5 mW, 0402 [1005 Metric], Thick Film, General Purpose"
			(at 237.49 226.06 0)
			(effects
				(font
					(size 1.27 1.27)
				)
				(hide yes)
			)
		)
		(property "Manufacturer" "Bourns"
			(at 257.81 248.92 0)
			(effects
				(font
					(size 1.27 1.27)
					(thickness 0.15)
				)
				(justify left bottom)
				(hide yes)
			)
		)
		(property "MPN" "CR0402-FX-1000GLF"
			(at 257.81 246.38 0)
			(effects
				(font
					(size 1.27 1.27)
					(thickness 0.15)
				)
				(justify left bottom)
				(hide yes)
			)
		)
		(property "Val" "100R"
			(at 240.03 222.25 0)
			(effects
				(font
					(size 1.27 1.27)
					(thickness 0.15)
				)
			)
		)
		(property "License" "Apache-2.0"
			(at 257.81 251.46 0)
			(effects
				(font
					(size 1.27 1.27)
					(thickness 0.15)
				)
				(justify left bottom)
				(hide yes)
			)
		)
		(property "Author" "Antmicro"
			(at 257.81 254 0)
			(effects
				(font
					(size 1.27 1.27)
					(thickness 0.15)
				)
				(justify left bottom)
				(hide yes)
			)
		)
		(property "Tolerance" "1%"
			(at 257.81 236.22 0)
			(effects
				(font
					(size 1.27 1.27)
				)
				(justify left bottom)
				(hide yes)
			)
		)
		(pin "1"
		)
		(pin "2"
		)
		(instances
			(project "sdi-mipi-video-converter"
				(path ""
					(reference "R72")
					(unit 1)
				)
			)
		)
	)
	(symbol
		(lib_id "antmicropower:+3.3V")
		(at 316.23 201.93 0)
		(mirror y)
		(unit 1)
		(exclude_from_sim no)
		(in_bom yes)
		(on_board yes)
		(dnp no)
		(fields_autoplaced yes)
		(property "Reference" "#PWR0177"
			(at 316.23 205.74 0)
			(effects
				(font
					(size 1.27 1.27)
				)
				(hide yes)
			)
		)
		(property "Value" "+3V3"
			(at 316.23 196.85 0)
			(effects
				(font
					(size 1.27 1.27)
				)
			)
		)
		(property "Footprint" ""
			(at 316.23 201.93 0)
			(effects
				(font
					(size 1.27 1.27)
				)
				(hide yes)
			)
		)
		(property "Datasheet" ""
			(at 316.23 201.93 0)
			(effects
				(font
					(size 1.27 1.27)
				)
				(hide yes)
			)
		)
		(property "Description" ""
			(at 316.23 201.93 0)
			(effects
				(font
					(size 1.27 1.27)
				)
				(hide yes)
			)
		)
		(pin "1"
		)
		(instances
			(project "sdi-mipi-video-converter"
				(path ""
					(reference "#PWR0177")
					(unit 1)
				)
			)
		)
	)
	(symbol
		(lib_id "antmicropower:GND")
		(at 227.33 90.17 0)
		(unit 1)
		(exclude_from_sim no)
		(in_bom yes)
		(on_board yes)
		(dnp no)
		(fields_autoplaced yes)
		(property "Reference" "#PWR018"
			(at 236.22 92.71 0)
			(effects
				(font
					(size 1.27 1.27)
					(thickness 0.15)
				)
				(justify left bottom)
				(hide yes)
			)
		)
		(property "Value" "GND"
			(at 227.33 95.25 0)
			(effects
				(font
					(size 1.27 1.27)
					(thickness 0.15)
				)
			)
		)
		(property "Footprint" ""
			(at 236.22 97.79 0)
			(effects
				(font
					(size 1.27 1.27)
					(thickness 0.15)
				)
				(justify left bottom)
				(hide yes)
			)
		)
		(property "Datasheet" ""
			(at 236.22 102.87 0)
			(effects
				(font
					(size 1.27 1.27)
					(thickness 0.15)
				)
				(justify left bottom)
				(hide yes)
			)
		)
		(property "Description" ""
			(at 227.33 90.17 0)
			(effects
				(font
					(size 1.27 1.27)
				)
				(hide yes)
			)
		)
		(property "Author" "Antmicro"
			(at 236.22 97.79 0)
			(effects
				(font
					(size 1.27 1.27)
					(thickness 0.15)
				)
				(justify left bottom)
				(hide yes)
			)
		)
		(property "License" "Apache-2.0"
			(at 236.22 100.33 0)
			(effects
				(font
					(size 1.27 1.27)
					(thickness 0.15)
				)
				(justify left bottom)
				(hide yes)
			)
		)
		(pin "1"
		)
		(instances
			(project "sdi-mipi-video-converter"
				(path ""
					(reference "#PWR018")
					(unit 1)
				)
			)
		)
	)
	(symbol
		(lib_id "antmicropower:GND")
		(at 142.24 269.24 0)
		(mirror y)
		(unit 1)
		(exclude_from_sim no)
		(in_bom yes)
		(on_board yes)
		(dnp no)
		(fields_autoplaced yes)
		(property "Reference" "#PWR0165"
			(at 133.35 271.78 0)
			(effects
				(font
					(size 1.27 1.27)
					(thickness 0.15)
				)
				(justify left bottom)
				(hide yes)
			)
		)
		(property "Value" "GND"
			(at 142.24 274.32 0)
			(effects
				(font
					(size 1.27 1.27)
					(thickness 0.15)
				)
			)
		)
		(property "Footprint" ""
			(at 133.35 276.86 0)
			(effects
				(font
					(size 1.27 1.27)
					(thickness 0.15)
				)
				(justify left bottom)
				(hide yes)
			)
		)
		(property "Datasheet" ""
			(at 133.35 281.94 0)
			(effects
				(font
					(size 1.27 1.27)
					(thickness 0.15)
				)
				(justify left bottom)
				(hide yes)
			)
		)
		(property "Description" ""
			(at 142.24 269.24 0)
			(effects
				(font
					(size 1.27 1.27)
				)
				(hide yes)
			)
		)
		(property "Author" "Antmicro"
			(at 133.35 276.86 0)
			(effects
				(font
					(size 1.27 1.27)
					(thickness 0.15)
				)
				(justify left bottom)
				(hide yes)
			)
		)
		(property "License" "Apache-2.0"
			(at 133.35 279.4 0)
			(effects
				(font
					(size 1.27 1.27)
					(thickness 0.15)
				)
				(justify left bottom)
				(hide yes)
			)
		)
		(pin "1"
		)
		(instances
			(project "sdi-mipi-video-converter"
				(path ""
					(reference "#PWR0165")
					(unit 1)
				)
			)
		)
	)
	(symbol
		(lib_id "antmicroResistors0402:R_100R_0402")
		(at 299.72 229.87 0)
		(unit 1)
		(exclude_from_sim no)
		(in_bom yes)
		(on_board yes)
		(dnp no)
		(fields_autoplaced yes)
		(property "Reference" "R84"
			(at 302.26 223.52 0)
			(effects
				(font
					(size 1.27 1.27)
					(thickness 0.15)
				)
			)
		)
		(property "Value" "R_100R_0402"
			(at 320.04 242.57 0)
			(effects
				(font
					(size 1.27 1.27)
					(thickness 0.15)
				)
				(justify left bottom)
				(hide yes)
			)
		)
		(property "Footprint" "antmicro-footprints:R_0402_1005Metric"
			(at 320.04 245.11 0)
			(effects
				(font
					(size 1.27 1.27)
					(thickness 0.15)
				)
				(justify left bottom)
				(hide yes)
			)
		)
		(property "Datasheet" "https://www.bourns.com/docs/product-datasheets/cr.pdf"
			(at 320.04 247.65 0)
			(effects
				(font
					(size 1.27 1.27)
					(thickness 0.15)
				)
				(justify left bottom)
				(hide yes)
			)
		)
		(property "Description" "SMD Chip Resistor, 100 ohm, ± 1%, 62.5 mW, 0402 [1005 Metric], Thick Film, General Purpose"
			(at 299.72 229.87 0)
			(effects
				(font
					(size 1.27 1.27)
				)
				(hide yes)
			)
		)
		(property "Manufacturer" "Bourns"
			(at 320.04 252.73 0)
			(effects
				(font
					(size 1.27 1.27)
					(thickness 0.15)
				)
				(justify left bottom)
				(hide yes)
			)
		)
		(property "MPN" "CR0402-FX-1000GLF"
			(at 320.04 250.19 0)
			(effects
				(font
					(size 1.27 1.27)
					(thickness 0.15)
				)
				(justify left bottom)
				(hide yes)
			)
		)
		(property "Val" "100R"
			(at 302.26 226.06 0)
			(effects
				(font
					(size 1.27 1.27)
					(thickness 0.15)
				)
			)
		)
		(property "License" "Apache-2.0"
			(at 320.04 255.27 0)
			(effects
				(font
					(size 1.27 1.27)
					(thickness 0.15)
				)
				(justify left bottom)
				(hide yes)
			)
		)
		(property "Author" "Antmicro"
			(at 320.04 257.81 0)
			(effects
				(font
					(size 1.27 1.27)
					(thickness 0.15)
				)
				(justify left bottom)
				(hide yes)
			)
		)
		(property "Tolerance" "1%"
			(at 320.04 240.03 0)
			(effects
				(font
					(size 1.27 1.27)
				)
				(justify left bottom)
				(hide yes)
			)
		)
		(pin "1"
		)
		(pin "2"
		)
		(instances
			(project "sdi-mipi-video-converter"
				(path ""
					(reference "R84")
					(unit 1)
				)
			)
		)
	)
	(symbol
		(lib_id "antmicroResistors0402:R_0R_0402")
		(at 279.4 87.63 0)
		(unit 1)
		(exclude_from_sim no)
		(in_bom yes)
		(on_board yes)
		(dnp no)
		(property "Reference" "R76"
			(at 277.495 88.9 0)
			(effects
				(font
					(size 1.27 1.27)
					(thickness 0.15)
				)
			)
		)
		(property "Value" "R_0R_0402"
			(at 299.72 100.33 0)
			(effects
				(font
					(size 1.27 1.27)
					(thickness 0.15)
				)
				(justify left bottom)
				(hide yes)
			)
		)
		(property "Footprint" "antmicro-footprints:R_0402_1005Metric"
			(at 299.72 102.87 0)
			(effects
				(font
					(size 1.27 1.27)
					(thickness 0.15)
				)
				(justify left bottom)
				(hide yes)
			)
		)
		(property "Datasheet" "https://industrial.panasonic.com/cdbs/www-data/pdf/RDA0000/AOA0000C301.pdf"
			(at 299.72 105.41 0)
			(effects
				(font
					(size 1.27 1.27)
					(thickness 0.15)
				)
				(justify left bottom)
				(hide yes)
			)
		)
		(property "Description" "SMD Chip Resistor, Jumper, 0 ohm, 100 mW, 0402 [1005 Metric], Thick Film, General Purpose"
			(at 279.4 87.63 0)
			(effects
				(font
					(size 1.27 1.27)
				)
				(hide yes)
			)
		)
		(property "Manufacturer" "Panasonic"
			(at 299.72 110.49 0)
			(effects
				(font
					(size 1.27 1.27)
					(thickness 0.15)
				)
				(justify left bottom)
				(hide yes)
			)
		)
		(property "MPN" "ERJ2GE0R00X"
			(at 299.72 107.95 0)
			(effects
				(font
					(size 1.27 1.27)
					(thickness 0.15)
				)
				(justify left bottom)
				(hide yes)
			)
		)
		(property "Val" "0R"
			(at 285.75 88.9 0)
			(effects
				(font
					(size 1.27 1.27)
					(thickness 0.15)
				)
			)
		)
		(property "License" "Apache-2.0"
			(at 299.72 113.03 0)
			(effects
				(font
					(size 1.27 1.27)
					(thickness 0.15)
				)
				(justify left bottom)
				(hide yes)
			)
		)
		(property "Author" "Antmicro"
			(at 299.72 115.57 0)
			(effects
				(font
					(size 1.27 1.27)
					(thickness 0.15)
				)
				(justify left bottom)
				(hide yes)
			)
		)
		(property "Tolerance" "~"
			(at 299.72 97.79 0)
			(effects
				(font
					(size 1.27 1.27)
				)
				(justify left bottom)
				(hide yes)
			)
		)
		(property "Current" "1A"
			(at 299.72 118.11 0)
			(effects
				(font
					(size 1.27 1.27)
					(thickness 0.15)
				)
				(justify left bottom)
				(hide yes)
			)
		)
		(pin "1"
		)
		(pin "2"
		)
		(instances
			(project "sdi-mipi-video-converter"
				(path ""
					(reference "R76")
					(unit 1)
				)
			)
		)
	)
	(symbol
		(lib_id "antmicroResistors0402:R_0R_0402")
		(at 370.84 115.57 0)
		(unit 1)
		(exclude_from_sim no)
		(in_bom yes)
		(on_board yes)
		(dnp no)
		(property "Reference" "R94"
			(at 368.935 114.3 0)
			(effects
				(font
					(size 1.27 1.27)
					(thickness 0.15)
				)
			)
		)
		(property "Value" "R_0R_0402"
			(at 391.16 128.27 0)
			(effects
				(font
					(size 1.27 1.27)
					(thickness 0.15)
				)
				(justify left bottom)
				(hide yes)
			)
		)
		(property "Footprint" "antmicro-footprints:R_0402_1005Metric"
			(at 391.16 130.81 0)
			(effects
				(font
					(size 1.27 1.27)
					(thickness 0.15)
				)
				(justify left bottom)
				(hide yes)
			)
		)
		(property "Datasheet" "https://industrial.panasonic.com/cdbs/www-data/pdf/RDA0000/AOA0000C301.pdf"
			(at 391.16 133.35 0)
			(effects
				(font
					(size 1.27 1.27)
					(thickness 0.15)
				)
				(justify left bottom)
				(hide yes)
			)
		)
		(property "Description" "SMD Chip Resistor, Jumper, 0 ohm, 100 mW, 0402 [1005 Metric], Thick Film, General Purpose"
			(at 370.84 115.57 0)
			(effects
				(font
					(size 1.27 1.27)
				)
				(hide yes)
			)
		)
		(property "Manufacturer" "Panasonic"
			(at 391.16 138.43 0)
			(effects
				(font
					(size 1.27 1.27)
					(thickness 0.15)
				)
				(justify left bottom)
				(hide yes)
			)
		)
		(property "MPN" "ERJ2GE0R00X"
			(at 391.16 135.89 0)
			(effects
				(font
					(size 1.27 1.27)
					(thickness 0.15)
				)
				(justify left bottom)
				(hide yes)
			)
		)
		(property "Val" "0R"
			(at 377.19 114.3 0)
			(effects
				(font
					(size 1.27 1.27)
					(thickness 0.15)
				)
			)
		)
		(property "License" "Apache-2.0"
			(at 391.16 140.97 0)
			(effects
				(font
					(size 1.27 1.27)
					(thickness 0.15)
				)
				(justify left bottom)
				(hide yes)
			)
		)
		(property "Author" "Antmicro"
			(at 391.16 143.51 0)
			(effects
				(font
					(size 1.27 1.27)
					(thickness 0.15)
				)
				(justify left bottom)
				(hide yes)
			)
		)
		(property "Tolerance" "~"
			(at 391.16 125.73 0)
			(effects
				(font
					(size 1.27 1.27)
				)
				(justify left bottom)
				(hide yes)
			)
		)
		(property "Current" "1A"
			(at 391.16 146.05 0)
			(effects
				(font
					(size 1.27 1.27)
					(thickness 0.15)
				)
				(justify left bottom)
				(hide yes)
			)
		)
		(pin "1"
		)
		(pin "2"
		)
		(instances
			(project "sdi-mipi-video-converter"
				(path ""
					(reference "R94")
					(unit 1)
				)
			)
		)
	)
	(symbol
		(lib_id "antmicropower:GND")
		(at 233.68 165.1 0)
		(mirror y)
		(unit 1)
		(exclude_from_sim no)
		(in_bom yes)
		(on_board yes)
		(dnp no)
		(fields_autoplaced yes)
		(property "Reference" "#PWR0175"
			(at 224.79 167.64 0)
			(effects
				(font
					(size 1.27 1.27)
					(thickness 0.15)
				)
				(justify left bottom)
				(hide yes)
			)
		)
		(property "Value" "GND"
			(at 233.68 170.18 0)
			(effects
				(font
					(size 1.27 1.27)
					(thickness 0.15)
				)
			)
		)
		(property "Footprint" ""
			(at 224.79 172.72 0)
			(effects
				(font
					(size 1.27 1.27)
					(thickness 0.15)
				)
				(justify left bottom)
				(hide yes)
			)
		)
		(property "Datasheet" ""
			(at 224.79 177.8 0)
			(effects
				(font
					(size 1.27 1.27)
					(thickness 0.15)
				)
				(justify left bottom)
				(hide yes)
			)
		)
		(property "Description" ""
			(at 233.68 165.1 0)
			(effects
				(font
					(size 1.27 1.27)
				)
				(hide yes)
			)
		)
		(property "Author" "Antmicro"
			(at 224.79 172.72 0)
			(effects
				(font
					(size 1.27 1.27)
					(thickness 0.15)
				)
				(justify left bottom)
				(hide yes)
			)
		)
		(property "License" "Apache-2.0"
			(at 224.79 175.26 0)
			(effects
				(font
					(size 1.27 1.27)
					(thickness 0.15)
				)
				(justify left bottom)
				(hide yes)
			)
		)
		(pin "1"
		)
		(instances
			(project "sdi-mipi-video-converter"
				(path ""
					(reference "#PWR0175")
					(unit 1)
				)
			)
		)
	)
	(symbol
		(lib_id "antmicroResistors0402:R_0R_0402")
		(at 284.48 77.47 180)
		(unit 1)
		(exclude_from_sim no)
		(in_bom yes)
		(on_board yes)
		(dnp no)
		(property "Reference" "R71"
			(at 277.495 78.74 0)
			(effects
				(font
					(size 1.27 1.27)
					(thickness 0.15)
				)
			)
		)
		(property "Value" "R_0R_0402"
			(at 264.16 64.77 0)
			(effects
				(font
					(size 1.27 1.27)
					(thickness 0.15)
				)
				(justify left bottom)
				(hide yes)
			)
		)
		(property "Footprint" "antmicro-footprints:R_0402_1005Metric"
			(at 264.16 62.23 0)
			(effects
				(font
					(size 1.27 1.27)
					(thickness 0.15)
				)
				(justify left bottom)
				(hide yes)
			)
		)
		(property "Datasheet" "https://industrial.panasonic.com/cdbs/www-data/pdf/RDA0000/AOA0000C301.pdf"
			(at 264.16 59.69 0)
			(effects
				(font
					(size 1.27 1.27)
					(thickness 0.15)
				)
				(justify left bottom)
				(hide yes)
			)
		)
		(property "Description" "SMD Chip Resistor, Jumper, 0 ohm, 100 mW, 0402 [1005 Metric], Thick Film, General Purpose"
			(at 284.48 77.47 0)
			(effects
				(font
					(size 1.27 1.27)
				)
				(hide yes)
			)
		)
		(property "Manufacturer" "Panasonic"
			(at 264.16 54.61 0)
			(effects
				(font
					(size 1.27 1.27)
					(thickness 0.15)
				)
				(justify left bottom)
				(hide yes)
			)
		)
		(property "MPN" "ERJ2GE0R00X"
			(at 264.16 57.15 0)
			(effects
				(font
					(size 1.27 1.27)
					(thickness 0.15)
				)
				(justify left bottom)
				(hide yes)
			)
		)
		(property "Val" "0R"
			(at 285.75 78.74 0)
			(effects
				(font
					(size 1.27 1.27)
					(thickness 0.15)
				)
			)
		)
		(property "License" "Apache-2.0"
			(at 264.16 52.07 0)
			(effects
				(font
					(size 1.27 1.27)
					(thickness 0.15)
				)
				(justify left bottom)
				(hide yes)
			)
		)
		(property "Author" "Antmicro"
			(at 264.16 49.53 0)
			(effects
				(font
					(size 1.27 1.27)
					(thickness 0.15)
				)
				(justify left bottom)
				(hide yes)
			)
		)
		(property "Tolerance" "~"
			(at 264.16 67.31 0)
			(effects
				(font
					(size 1.27 1.27)
				)
				(justify left bottom)
				(hide yes)
			)
		)
		(property "Current" "1A"
			(at 264.16 46.99 0)
			(effects
				(font
					(size 1.27 1.27)
					(thickness 0.15)
				)
				(justify left bottom)
				(hide yes)
			)
		)
		(pin "1"
		)
		(pin "2"
		)
		(instances
			(project "sdi-mipi-video-converter"
				(path ""
					(reference "R71")
					(unit 1)
				)
			)
		)
	)
	(symbol
		(lib_id "antmicroTestPoints:TP_0.75mm_SMD")
		(at 285.75 50.8 90)
		(unit 1)
		(exclude_from_sim no)
		(in_bom yes)
		(on_board yes)
		(dnp no)
		(property "Reference" "TP15"
			(at 285.75 43.815 0)
			(effects
				(font
					(size 1.27 1.27)
					(thickness 0.15)
				)
			)
		)
		(property "Value" "TP_0.75mm_SMD"
			(at 293.37 33.02 0)
			(effects
				(font
					(size 1.27 1.27)
					(thickness 0.15)
				)
				(justify left bottom)
				(hide yes)
			)
		)
		(property "Footprint" "antmicro-footprints:TP_SMD_0.75mm"
			(at 295.91 33.02 0)
			(effects
				(font
					(size 1.27 1.27)
					(thickness 0.15)
				)
				(justify left bottom)
				(hide yes)
			)
		)
		(property "Datasheet" ""
			(at 298.45 33.02 0)
			(effects
				(font
					(size 1.27 1.27)
					(thickness 0.15)
				)
				(justify left bottom)
				(hide yes)
			)
		)
		(property "Description" "SMT test point"
			(at 285.75 50.8 0)
			(effects
				(font
					(size 1.27 1.27)
				)
				(hide yes)
			)
		)
		(property "MPN" ""
			(at 300.99 33.02 0)
			(effects
				(font
					(size 1.27 1.27)
					(thickness 0.15)
				)
				(justify left bottom)
				(hide yes)
			)
		)
		(property "Manufacturer" ""
			(at 303.53 33.02 0)
			(effects
				(font
					(size 1.27 1.27)
					(thickness 0.15)
				)
				(justify left bottom)
				(hide yes)
			)
		)
		(property "Author" "Antmicro"
			(at 306.07 33.02 0)
			(effects
				(font
					(size 1.27 1.27)
					(thickness 0.15)
				)
				(justify left bottom)
				(hide yes)
			)
		)
		(property "License" "Apache-2.0"
			(at 308.61 33.02 0)
			(effects
				(font
					(size 1.27 1.27)
					(thickness 0.15)
				)
				(justify left bottom)
				(hide yes)
			)
		)
		(pin "1"
		)
		(instances
			(project "sdi-mipi-video-converter"
				(path ""
					(reference "TP15")
					(unit 1)
				)
			)
		)
	)
	(symbol
		(lib_id "antmicroTestPoints:TP_0.75mm_SMD")
		(at 297.18 50.8 90)
		(unit 1)
		(exclude_from_sim no)
		(in_bom yes)
		(on_board yes)
		(dnp no)
		(property "Reference" "TP18"
			(at 297.18 43.815 0)
			(effects
				(font
					(size 1.27 1.27)
					(thickness 0.15)
				)
			)
		)
		(property "Value" "TP_0.75mm_SMD"
			(at 304.8 33.02 0)
			(effects
				(font
					(size 1.27 1.27)
					(thickness 0.15)
				)
				(justify left bottom)
				(hide yes)
			)
		)
		(property "Footprint" "antmicro-footprints:TP_SMD_0.75mm"
			(at 307.34 33.02 0)
			(effects
				(font
					(size 1.27 1.27)
					(thickness 0.15)
				)
				(justify left bottom)
				(hide yes)
			)
		)
		(property "Datasheet" ""
			(at 309.88 33.02 0)
			(effects
				(font
					(size 1.27 1.27)
					(thickness 0.15)
				)
				(justify left bottom)
				(hide yes)
			)
		)
		(property "Description" "SMT test point"
			(at 297.18 50.8 0)
			(effects
				(font
					(size 1.27 1.27)
				)
				(hide yes)
			)
		)
		(property "MPN" ""
			(at 312.42 33.02 0)
			(effects
				(font
					(size 1.27 1.27)
					(thickness 0.15)
				)
				(justify left bottom)
				(hide yes)
			)
		)
		(property "Manufacturer" ""
			(at 314.96 33.02 0)
			(effects
				(font
					(size 1.27 1.27)
					(thickness 0.15)
				)
				(justify left bottom)
				(hide yes)
			)
		)
		(property "Author" "Antmicro"
			(at 317.5 33.02 0)
			(effects
				(font
					(size 1.27 1.27)
					(thickness 0.15)
				)
				(justify left bottom)
				(hide yes)
			)
		)
		(property "License" "Apache-2.0"
			(at 320.04 33.02 0)
			(effects
				(font
					(size 1.27 1.27)
					(thickness 0.15)
				)
				(justify left bottom)
				(hide yes)
			)
		)
		(pin "1"
		)
		(instances
			(project "sdi-mipi-video-converter"
				(path ""
					(reference "TP18")
					(unit 1)
				)
			)
		)
	)
	(symbol
		(lib_id "antmicroOscillators:Oscillator_40MHz_YIC_OSC-S5")
		(at 148.59 257.81 0)
		(unit 1)
		(exclude_from_sim no)
		(in_bom yes)
		(on_board yes)
		(dnp no)
		(fields_autoplaced yes)
		(property "Reference" "Y2"
			(at 158.115 250.19 0)
			(effects
				(font
					(size 1.27 1.27)
					(thickness 0.15)
				)
			)
		)
		(property "Value" "Oscillator_SMD_40MHz_OSC-S5"
			(at 158.115 252.73 0)
			(effects
				(font
					(size 1.27 1.27)
					(thickness 0.15)
				)
			)
		)
		(property "Footprint" "antmicro-footprints:Oscillator_SMD_YIC_OSC-S5_5x3.2mm"
			(at 181.61 265.43 0)
			(effects
				(font
					(size 1.27 1.27)
					(thickness 0.15)
				)
				(justify left bottom)
				(hide yes)
			)
		)
		(property "Datasheet" "https://www.tme.eu/Document/456c7b2975a812de7905406dd4f750d9/YIC-S5.pdf"
			(at 181.61 267.97 0)
			(effects
				(font
					(size 1.27 1.27)
					(thickness 0.15)
				)
				(justify left bottom)
				(hide yes)
			)
		)
		(property "Description" "Generator: quartz, 40MHz, SMD, 3.3V, ±50ppm, -20÷70°C, 5x3.2x1.3mm"
			(at 148.59 257.81 0)
			(effects
				(font
					(size 1.27 1.27)
				)
				(hide yes)
			)
		)
		(property "MPN" "OSC40M-3.3/S5"
			(at 181.61 270.51 0)
			(effects
				(font
					(size 1.27 1.27)
					(thickness 0.15)
				)
				(justify left bottom)
				(hide yes)
			)
		)
		(property "Manufacturer" "YIC"
			(at 181.61 273.05 0)
			(effects
				(font
					(size 1.27 1.27)
					(thickness 0.15)
				)
				(justify left bottom)
				(hide yes)
			)
		)
		(property "Author" "Antmicro"
			(at 181.61 275.59 0)
			(effects
				(font
					(size 1.27 1.27)
					(thickness 0.15)
				)
				(justify left bottom)
				(hide yes)
			)
		)
		(property "License" "Apache-2.0"
			(at 181.61 278.13 0)
			(effects
				(font
					(size 1.27 1.27)
					(thickness 0.15)
				)
				(justify left bottom)
				(hide yes)
			)
		)
		(property "Val" "40 MHz"
			(at 158.115 252.73 0)
			(effects
				(font
					(size 1.27 1.27)
					(thickness 0.15)
				)
				(hide yes)
			)
		)
		(pin "1"
		)
		(pin "2"
		)
		(pin "3"
		)
		(pin "4"
		)
		(instances
			(project "sdi-mipi-video-converter"
				(path ""
					(reference "Y2")
					(unit 1)
				)
			)
		)
	)
	(symbol
		(lib_id "antmicropower:GND")
		(at 349.25 134.62 0)
		(unit 1)
		(exclude_from_sim no)
		(in_bom yes)
		(on_board yes)
		(dnp no)
		(fields_autoplaced yes)
		(property "Reference" "#PWR0182"
			(at 358.14 137.16 0)
			(effects
				(font
					(size 1.27 1.27)
					(thickness 0.15)
				)
				(justify left bottom)
				(hide yes)
			)
		)
		(property "Value" "GND"
			(at 349.25 139.7 0)
			(effects
				(font
					(size 1.27 1.27)
					(thickness 0.15)
				)
			)
		)
		(property "Footprint" ""
			(at 358.14 142.24 0)
			(effects
				(font
					(size 1.27 1.27)
					(thickness 0.15)
				)
				(justify left bottom)
				(hide yes)
			)
		)
		(property "Datasheet" ""
			(at 358.14 147.32 0)
			(effects
				(font
					(size 1.27 1.27)
					(thickness 0.15)
				)
				(justify left bottom)
				(hide yes)
			)
		)
		(property "Description" ""
			(at 349.25 134.62 0)
			(effects
				(font
					(size 1.27 1.27)
				)
				(hide yes)
			)
		)
		(property "Author" "Antmicro"
			(at 358.14 142.24 0)
			(effects
				(font
					(size 1.27 1.27)
					(thickness 0.15)
				)
				(justify left bottom)
				(hide yes)
			)
		)
		(property "License" "Apache-2.0"
			(at 358.14 144.78 0)
			(effects
				(font
					(size 1.27 1.27)
					(thickness 0.15)
				)
				(justify left bottom)
				(hide yes)
			)
		)
		(pin "1"
		)
		(instances
			(project "sdi-mipi-video-converter"
				(path ""
					(reference "#PWR0182")
					(unit 1)
				)
			)
		)
	)
	(symbol
		(lib_id "antmicroResistors0603:R_0R_0603")
		(at 233.68 144.78 180)
		(unit 1)
		(exclude_from_sim no)
		(in_bom yes)
		(on_board yes)
		(dnp no)
		(property "Reference" "R58"
			(at 235.585 143.51 0)
			(effects
				(font
					(size 1.27 1.27)
					(thickness 0.15)
				)
			)
		)
		(property "Value" "R_0R_0603"
			(at 213.36 132.08 0)
			(effects
				(font
					(size 1.27 1.27)
					(thickness 0.15)
				)
				(justify left bottom)
				(hide yes)
			)
		)
		(property "Footprint" "antmicro-footprints:R_0603_1608Metric"
			(at 213.36 129.54 0)
			(effects
				(font
					(size 1.27 1.27)
					(thickness 0.15)
				)
				(justify left bottom)
				(hide yes)
			)
		)
		(property "Datasheet" "https://www.bourns.com/docs/product-datasheets/cr.pdf?sfvrsn=574d41f6_14"
			(at 213.36 127 0)
			(effects
				(font
					(size 1.27 1.27)
					(thickness 0.15)
				)
				(justify left bottom)
				(hide yes)
			)
		)
		(property "Description" "Zero Ohm Resistor, Jumper, 0603 [1608 Metric], Thick Film, 100 mW, 1 A, Surface Mount Device, CR"
			(at 233.68 144.78 0)
			(effects
				(font
					(size 1.27 1.27)
				)
				(hide yes)
			)
		)
		(property "Manufacturer" "Bourns"
			(at 213.36 121.92 0)
			(effects
				(font
					(size 1.27 1.27)
					(thickness 0.15)
				)
				(justify left bottom)
				(hide yes)
			)
		)
		(property "MPN" "CR0603-J/-000ELF"
			(at 213.36 124.46 0)
			(effects
				(font
					(size 1.27 1.27)
					(thickness 0.15)
				)
				(justify left bottom)
				(hide yes)
			)
		)
		(property "Val" "0R"
			(at 227.33 143.51 0)
			(effects
				(font
					(size 1.27 1.27)
					(thickness 0.15)
				)
			)
		)
		(property "License" "Apache-2.0"
			(at 213.36 119.38 0)
			(effects
				(font
					(size 1.27 1.27)
					(thickness 0.15)
				)
				(justify left bottom)
				(hide yes)
			)
		)
		(property "Author" "Antmicro"
			(at 213.36 116.84 0)
			(effects
				(font
					(size 1.27 1.27)
					(thickness 0.15)
				)
				(justify left bottom)
				(hide yes)
			)
		)
		(property "Tolerance" "~"
			(at 213.36 134.62 0)
			(effects
				(font
					(size 1.27 1.27)
				)
				(justify left bottom)
				(hide yes)
			)
		)
		(property "Current" "1A"
			(at 213.36 114.3 0)
			(effects
				(font
					(size 1.27 1.27)
					(thickness 0.15)
				)
				(justify left bottom)
				(hide yes)
			)
		)
		(pin "1"
		)
		(pin "2"
		)
		(instances
			(project "sdi-mipi-video-converter"
				(path ""
					(reference "R58")
					(unit 1)
				)
			)
		)
	)
	(symbol
		(lib_id "antmicroResistors0402:R_10k_0402")
		(at 361.95 219.71 90)
		(unit 1)
		(exclude_from_sim no)
		(in_bom yes)
		(on_board yes)
		(dnp no)
		(fields_autoplaced yes)
		(property "Reference" "R91"
			(at 364.49 215.8999 90)
			(effects
				(font
					(size 1.27 1.27)
					(thickness 0.15)
				)
				(justify right)
			)
		)
		(property "Value" "R_10k_0402"
			(at 374.65 199.39 0)
			(effects
				(font
					(size 1.27 1.27)
					(thickness 0.15)
				)
				(justify left bottom)
				(hide yes)
			)
		)
		(property "Footprint" "antmicro-footprints:R_0402_1005Metric"
			(at 377.19 199.39 0)
			(effects
				(font
					(size 1.27 1.27)
					(thickness 0.15)
				)
				(justify left bottom)
				(hide yes)
			)
		)
		(property "Datasheet" "https://www.bourns.com/docs/product-datasheets/cr.pdf"
			(at 379.73 199.39 0)
			(effects
				(font
					(size 1.27 1.27)
					(thickness 0.15)
				)
				(justify left bottom)
				(hide yes)
			)
		)
		(property "Description" "SMD Chip Resistor, 10 kohm, ± 1%, 62.5 mW, 0402 [1005 Metric], Thick Film, General Purpose"
			(at 361.95 219.71 0)
			(effects
				(font
					(size 1.27 1.27)
				)
				(hide yes)
			)
		)
		(property "Manufacturer" "Bourns"
			(at 384.81 199.39 0)
			(effects
				(font
					(size 1.27 1.27)
					(thickness 0.15)
				)
				(justify left bottom)
				(hide yes)
			)
		)
		(property "MPN" "CR0402-FX-1002GLF"
			(at 382.27 199.39 0)
			(effects
				(font
					(size 1.27 1.27)
					(thickness 0.15)
				)
				(justify left bottom)
				(hide yes)
			)
		)
		(property "Val" "10k"
			(at 364.49 218.4399 90)
			(effects
				(font
					(size 1.27 1.27)
					(thickness 0.15)
				)
				(justify right)
			)
		)
		(property "License" "Apache-2.0"
			(at 387.35 199.39 0)
			(effects
				(font
					(size 1.27 1.27)
					(thickness 0.15)
				)
				(justify left bottom)
				(hide yes)
			)
		)
		(property "Author" "Antmicro"
			(at 389.89 199.39 0)
			(effects
				(font
					(size 1.27 1.27)
					(thickness 0.15)
				)
				(justify left bottom)
				(hide yes)
			)
		)
		(property "Tolerance" "1%"
			(at 372.11 199.39 0)
			(effects
				(font
					(size 1.27 1.27)
				)
				(justify left bottom)
				(hide yes)
			)
		)
		(pin "1"
		)
		(pin "2"
		)
		(instances
			(project "sdi-mipi-video-converter"
				(path ""
					(reference "R91")
					(unit 1)
				)
			)
		)
	)
	(symbol
		(lib_id "antmicropower:+3.3V")
		(at 142.24 251.46 0)
		(mirror y)
		(unit 1)
		(exclude_from_sim no)
		(in_bom yes)
		(on_board yes)
		(dnp no)
		(fields_autoplaced yes)
		(property "Reference" "#PWR0164"
			(at 142.24 255.27 0)
			(effects
				(font
					(size 1.27 1.27)
				)
				(hide yes)
			)
		)
		(property "Value" "+3V3"
			(at 142.24 246.38 0)
			(effects
				(font
					(size 1.27 1.27)
				)
			)
		)
		(property "Footprint" ""
			(at 142.24 251.46 0)
			(effects
				(font
					(size 1.27 1.27)
				)
				(hide yes)
			)
		)
		(property "Datasheet" ""
			(at 142.24 251.46 0)
			(effects
				(font
					(size 1.27 1.27)
				)
				(hide yes)
			)
		)
		(property "Description" ""
			(at 142.24 251.46 0)
			(effects
				(font
					(size 1.27 1.27)
				)
				(hide yes)
			)
		)
		(pin "1"
		)
		(instances
			(project "sdi-mipi-video-converter"
				(path ""
					(reference "#PWR0164")
					(unit 1)
				)
			)
		)
	)
	(symbol
		(lib_id "antmicroPushbuttonSwitches:SW_B3U-3000PM_SMD")
		(at 251.46 238.76 90)
		(unit 1)
		(exclude_from_sim no)
		(in_bom yes)
		(on_board yes)
		(dnp no)
		(fields_autoplaced yes)
		(property "Reference" "S1"
			(at 252.73 232.4099 90)
			(effects
				(font
					(size 1.27 1.27)
					(thickness 0.15)
				)
				(justify right)
			)
		)
		(property "Value" "SW_B3U-3000PM"
			(at 252.73 234.9499 90)
			(effects
				(font
					(size 1.27 1.27)
					(thickness 0.15)
				)
				(justify right)
			)
		)
		(property "Footprint" "antmicro-footprints:SW_B3U-3000PM_SMD"
			(at 259.08 213.36 0)
			(effects
				(font
					(size 1.27 1.27)
					(thickness 0.15)
				)
				(justify left bottom)
				(hide yes)
			)
		)
		(property "Datasheet" "http://www.farnell.com/datasheets/2610940.pdf"
			(at 261.62 213.36 0)
			(effects
				(font
					(size 1.27 1.27)
					(thickness 0.15)
				)
				(justify left bottom)
				(hide yes)
			)
		)
		(property "Description" "Tactile Switch SPST-NO Side Actuated Surface Mount, Right Angle"
			(at 251.46 238.76 0)
			(effects
				(font
					(size 1.27 1.27)
				)
				(hide yes)
			)
		)
		(property "MPN" "B3U-3000PM"
			(at 264.16 213.36 0)
			(effects
				(font
					(size 1.27 1.27)
					(thickness 0.15)
				)
				(justify left bottom)
				(hide yes)
			)
		)
		(property "Manufacturer" "Omron"
			(at 266.7 213.36 0)
			(effects
				(font
					(size 1.27 1.27)
					(thickness 0.15)
				)
				(justify left bottom)
				(hide yes)
			)
		)
		(property "Author" "Antmicro"
			(at 269.24 213.36 0)
			(effects
				(font
					(size 1.27 1.27)
					(thickness 0.15)
				)
				(justify left bottom)
				(hide yes)
			)
		)
		(property "License" "Apache-2.0"
			(at 271.78 213.36 0)
			(effects
				(font
					(size 1.27 1.27)
					(thickness 0.15)
				)
				(justify left bottom)
				(hide yes)
			)
		)
		(pin "1"
		)
		(pin "2"
		)
		(instances
			(project "sdi-mipi-video-converter"
				(path ""
					(reference "S1")
					(unit 1)
				)
			)
		)
	)
	(symbol
		(lib_id "antmicroResistors0402:R_0R_0402")
		(at 370.84 105.41 0)
		(unit 1)
		(exclude_from_sim no)
		(in_bom yes)
		(on_board yes)
		(dnp no)
		(property "Reference" "R88"
			(at 368.935 104.14 0)
			(effects
				(font
					(size 1.27 1.27)
					(thickness 0.15)
				)
			)
		)
		(property "Value" "R_0R_0402"
			(at 391.16 118.11 0)
			(effects
				(font
					(size 1.27 1.27)
					(thickness 0.15)
				)
				(justify left bottom)
				(hide yes)
			)
		)
		(property "Footprint" "antmicro-footprints:R_0402_1005Metric"
			(at 391.16 120.65 0)
			(effects
				(font
					(size 1.27 1.27)
					(thickness 0.15)
				)
				(justify left bottom)
				(hide yes)
			)
		)
		(property "Datasheet" "https://industrial.panasonic.com/cdbs/www-data/pdf/RDA0000/AOA0000C301.pdf"
			(at 391.16 123.19 0)
			(effects
				(font
					(size 1.27 1.27)
					(thickness 0.15)
				)
				(justify left bottom)
				(hide yes)
			)
		)
		(property "Description" "SMD Chip Resistor, Jumper, 0 ohm, 100 mW, 0402 [1005 Metric], Thick Film, General Purpose"
			(at 370.84 105.41 0)
			(effects
				(font
					(size 1.27 1.27)
				)
				(hide yes)
			)
		)
		(property "Manufacturer" "Panasonic"
			(at 391.16 128.27 0)
			(effects
				(font
					(size 1.27 1.27)
					(thickness 0.15)
				)
				(justify left bottom)
				(hide yes)
			)
		)
		(property "MPN" "ERJ2GE0R00X"
			(at 391.16 125.73 0)
			(effects
				(font
					(size 1.27 1.27)
					(thickness 0.15)
				)
				(justify left bottom)
				(hide yes)
			)
		)
		(property "Val" "0R"
			(at 377.19 104.14 0)
			(effects
				(font
					(size 1.27 1.27)
					(thickness 0.15)
				)
			)
		)
		(property "License" "Apache-2.0"
			(at 391.16 130.81 0)
			(effects
				(font
					(size 1.27 1.27)
					(thickness 0.15)
				)
				(justify left bottom)
				(hide yes)
			)
		)
		(property "Author" "Antmicro"
			(at 391.16 133.35 0)
			(effects
				(font
					(size 1.27 1.27)
					(thickness 0.15)
				)
				(justify left bottom)
				(hide yes)
			)
		)
		(property "Tolerance" "~"
			(at 391.16 115.57 0)
			(effects
				(font
					(size 1.27 1.27)
				)
				(justify left bottom)
				(hide yes)
			)
		)
		(property "Current" "1A"
			(at 391.16 135.89 0)
			(effects
				(font
					(size 1.27 1.27)
					(thickness 0.15)
				)
				(justify left bottom)
				(hide yes)
			)
		)
		(pin "1"
		)
		(pin "2"
		)
		(instances
			(project "sdi-mipi-video-converter"
				(path ""
					(reference "R88")
					(unit 1)
				)
			)
		)
	)
	(symbol
		(lib_id "antmicroCapacitors0402:C_100n_0402")
		(at 257.81 86.36 270)
		(unit 1)
		(exclude_from_sim no)
		(in_bom yes)
		(on_board yes)
		(dnp no)
		(property "Reference" "C125"
			(at 258.445 90.805 90)
			(effects
				(font
					(size 1.27 1.27)
					(thickness 0.15)
				)
				(justify left)
			)
		)
		(property "Value" "C_100n_0402"
			(at 247.65 106.68 0)
			(effects
				(font
					(size 1.27 1.27)
					(thickness 0.15)
				)
				(justify left bottom)
				(hide yes)
			)
		)
		(property "Footprint" "antmicro-footprints:C_0402_1005Metric"
			(at 245.11 106.68 0)
			(effects
				(font
					(size 1.27 1.27)
					(thickness 0.15)
				)
				(justify left bottom)
				(hide yes)
			)
		)
		(property "Datasheet" "https://www.murata.com/products/productdetail?partno=GRM155R61H104KE14%23"
			(at 242.57 106.68 0)
			(effects
				(font
					(size 1.27 1.27)
					(thickness 0.15)
				)
				(justify left bottom)
				(hide yes)
			)
		)
		(property "Description" "SMD Multilayer Ceramic Capacitor, 0.1 µF, 50 V, 0402 [1005 Metric], ± 10%, X5R, GRM Series"
			(at 257.81 86.36 0)
			(effects
				(font
					(size 1.27 1.27)
				)
				(hide yes)
			)
		)
		(property "Manufacturer" "Murata"
			(at 237.49 106.68 0)
			(effects
				(font
					(size 1.27 1.27)
					(thickness 0.15)
				)
				(justify left bottom)
				(hide yes)
			)
		)
		(property "MPN" "GRM155R61H104KE14D"
			(at 240.03 106.68 0)
			(effects
				(font
					(size 1.27 1.27)
					(thickness 0.15)
				)
				(justify left bottom)
				(hide yes)
			)
		)
		(property "Val" "100n"
			(at 258.445 92.71 90)
			(effects
				(font
					(size 1.27 1.27)
					(thickness 0.15)
				)
				(justify left)
			)
		)
		(property "License" "Apache-2.0"
			(at 234.95 106.68 0)
			(effects
				(font
					(size 1.27 1.27)
					(thickness 0.15)
				)
				(justify left bottom)
				(hide yes)
			)
		)
		(property "Author" "Antmicro"
			(at 232.41 106.68 0)
			(effects
				(font
					(size 1.27 1.27)
					(thickness 0.15)
				)
				(justify left bottom)
				(hide yes)
			)
		)
		(property "Voltage" "50V"
			(at 229.87 106.68 0)
			(effects
				(font
					(size 1.27 1.27)
				)
				(justify left bottom)
				(hide yes)
			)
		)
		(property "Dielectric" "X5R"
			(at 227.33 106.68 0)
			(effects
				(font
					(size 1.27 1.27)
				)
				(justify left bottom)
				(hide yes)
			)
		)
		(pin "1"
		)
		(pin "2"
		)
		(instances
			(project "sdi-mipi-video-converter"
				(path ""
					(reference "C125")
					(unit 1)
				)
			)
		)
	)
	(symbol
		(lib_id "antmicropower:GND")
		(at 316.23 234.95 0)
		(unit 1)
		(exclude_from_sim no)
		(in_bom yes)
		(on_board yes)
		(dnp no)
		(fields_autoplaced yes)
		(property "Reference" "#PWR0178"
			(at 325.12 237.49 0)
			(effects
				(font
					(size 1.27 1.27)
					(thickness 0.15)
				)
				(justify left bottom)
				(hide yes)
			)
		)
		(property "Value" "GND"
			(at 316.23 240.03 0)
			(effects
				(font
					(size 1.27 1.27)
					(thickness 0.15)
				)
			)
		)
		(property "Footprint" ""
			(at 325.12 242.57 0)
			(effects
				(font
					(size 1.27 1.27)
					(thickness 0.15)
				)
				(justify left bottom)
				(hide yes)
			)
		)
		(property "Datasheet" ""
			(at 325.12 247.65 0)
			(effects
				(font
					(size 1.27 1.27)
					(thickness 0.15)
				)
				(justify left bottom)
				(hide yes)
			)
		)
		(property "Description" ""
			(at 316.23 234.95 0)
			(effects
				(font
					(size 1.27 1.27)
				)
				(hide yes)
			)
		)
		(property "Author" "Antmicro"
			(at 325.12 242.57 0)
			(effects
				(font
					(size 1.27 1.27)
					(thickness 0.15)
				)
				(justify left bottom)
				(hide yes)
			)
		)
		(property "License" "Apache-2.0"
			(at 325.12 245.11 0)
			(effects
				(font
					(size 1.27 1.27)
					(thickness 0.15)
				)
				(justify left bottom)
				(hide yes)
			)
		)
		(pin "1"
		)
		(instances
			(project "sdi-mipi-video-converter"
				(path ""
					(reference "#PWR0178")
					(unit 1)
				)
			)
		)
	)
	(symbol
		(lib_id "antmicroResistors0402:R_0R_0402")
		(at 284.48 72.39 180)
		(unit 1)
		(exclude_from_sim no)
		(in_bom yes)
		(on_board yes)
		(dnp no)
		(property "Reference" "R69"
			(at 277.495 73.66 0)
			(effects
				(font
					(size 1.27 1.27)
					(thickness 0.15)
				)
			)
		)
		(property "Value" "R_0R_0402"
			(at 264.16 59.69 0)
			(effects
				(font
					(size 1.27 1.27)
					(thickness 0.15)
				)
				(justify left bottom)
				(hide yes)
			)
		)
		(property "Footprint" "antmicro-footprints:R_0402_1005Metric"
			(at 264.16 57.15 0)
			(effects
				(font
					(size 1.27 1.27)
					(thickness 0.15)
				)
				(justify left bottom)
				(hide yes)
			)
		)
		(property "Datasheet" "https://industrial.panasonic.com/cdbs/www-data/pdf/RDA0000/AOA0000C301.pdf"
			(at 264.16 54.61 0)
			(effects
				(font
					(size 1.27 1.27)
					(thickness 0.15)
				)
				(justify left bottom)
				(hide yes)
			)
		)
		(property "Description" "SMD Chip Resistor, Jumper, 0 ohm, 100 mW, 0402 [1005 Metric], Thick Film, General Purpose"
			(at 284.48 72.39 0)
			(effects
				(font
					(size 1.27 1.27)
				)
				(hide yes)
			)
		)
		(property "Manufacturer" "Panasonic"
			(at 264.16 49.53 0)
			(effects
				(font
					(size 1.27 1.27)
					(thickness 0.15)
				)
				(justify left bottom)
				(hide yes)
			)
		)
		(property "MPN" "ERJ2GE0R00X"
			(at 264.16 52.07 0)
			(effects
				(font
					(size 1.27 1.27)
					(thickness 0.15)
				)
				(justify left bottom)
				(hide yes)
			)
		)
		(property "Val" "0R"
			(at 285.75 73.66 0)
			(effects
				(font
					(size 1.27 1.27)
					(thickness 0.15)
				)
			)
		)
		(property "License" "Apache-2.0"
			(at 264.16 46.99 0)
			(effects
				(font
					(size 1.27 1.27)
					(thickness 0.15)
				)
				(justify left bottom)
				(hide yes)
			)
		)
		(property "Author" "Antmicro"
			(at 264.16 44.45 0)
			(effects
				(font
					(size 1.27 1.27)
					(thickness 0.15)
				)
				(justify left bottom)
				(hide yes)
			)
		)
		(property "Tolerance" "~"
			(at 264.16 62.23 0)
			(effects
				(font
					(size 1.27 1.27)
				)
				(justify left bottom)
				(hide yes)
			)
		)
		(property "Current" "1A"
			(at 264.16 41.91 0)
			(effects
				(font
					(size 1.27 1.27)
					(thickness 0.15)
				)
				(justify left bottom)
				(hide yes)
			)
		)
		(pin "1"
		)
		(pin "2"
		)
		(instances
			(project "sdi-mipi-video-converter"
				(path ""
					(reference "R69")
					(unit 1)
				)
			)
		)
	)
	(symbol
		(lib_id "antmicroFPGAChips:CrossLink_LIFCL-40-9BG256C")
		(at 138.43 130.81 0)
		(mirror y)
		(unit 12)
		(exclude_from_sim no)
		(in_bom yes)
		(on_board yes)
		(dnp no)
		(fields_autoplaced yes)
		(property "Reference" "U11"
			(at 123.825 123.19 0)
			(effects
				(font
					(size 1.27 1.27)
					(thickness 0.15)
				)
			)
		)
		(property "Value" "LIFCL-40-9BG256C"
			(at 123.825 123.19 0)
			(effects
				(font
					(size 1.27 1.27)
					(thickness 0.15)
				)
				(hide yes)
			)
		)
		(property "Footprint" "antmicro-footprints:BGA-256_14x14mm_Layout16x16_P0.8mm"
			(at 85.09 138.43 0)
			(effects
				(font
					(size 1.27 1.27)
					(thickness 0.15)
				)
				(justify left bottom)
				(hide yes)
			)
		)
		(property "Datasheet" "https://www.latticesemi.com/-/media/LatticeSemi/Documents/DataSheets/CrossLink/FPGA-DS-02007-2-1-CrossLink-Family-Data-Sheet.ashx?document_id=51662"
			(at 85.09 140.97 0)
			(effects
				(font
					(size 1.27 1.27)
					(thickness 0.15)
				)
				(justify left bottom)
				(hide yes)
			)
		)
		(property "Description" "CrossLink-NX™ Field Programmable Gate Array 256-LFBGA"
			(at 138.43 130.81 0)
			(effects
				(font
					(size 1.27 1.27)
				)
				(hide yes)
			)
		)
		(property "MPN" "LIFCL-40-9BG256C"
			(at 123.825 125.73 0)
			(effects
				(font
					(size 1.27 1.27)
					(thickness 0.15)
				)
			)
		)
		(property "Manufacturer" "Lattice Semiconductor"
			(at 85.09 143.51 0)
			(effects
				(font
					(size 1.27 1.27)
					(thickness 0.15)
				)
				(justify left bottom)
				(hide yes)
			)
		)
		(property "Author" "Antmicro"
			(at 85.09 146.05 0)
			(effects
				(font
					(size 1.27 1.27)
					(thickness 0.15)
				)
				(justify left bottom)
				(hide yes)
			)
		)
		(property "License" "Apache-2.0"
			(at 85.09 148.59 0)
			(effects
				(font
					(size 1.27 1.27)
					(thickness 0.15)
				)
				(justify left bottom)
				(hide yes)
			)
		)
		(pin "B16"
		)
		(pin "C12"
		)
		(pin "C13"
		)
		(pin "C14"
		)
		(pin "C15"
		)
		(pin "C16"
		)
		(pin "D11"
		)
		(pin "D12"
		)
		(pin "D13"
		)
		(pin "D15"
		)
		(pin "D16"
		)
		(pin "E15"
		)
		(pin "E16"
		)
		(pin "D10"
		)
		(pin "E10"
		)
		(pin "E11"
		)
		(pin "E12"
		)
		(pin "E13"
		)
		(pin "E14"
		)
		(pin "E9"
		)
		(pin "F10"
		)
		(pin "F11"
		)
		(pin "F13"
		)
		(pin "F14"
		)
		(pin "F15"
		)
		(pin "F16"
		)
		(pin "F9"
		)
		(pin "G10"
		)
		(pin "G11"
		)
		(pin "G12"
		)
		(pin "G13"
		)
		(pin "G14"
		)
		(pin "G15"
		)
		(pin "G16"
		)
		(pin "G9"
		)
		(pin "H10"
		)
		(pin "H11"
		)
		(pin "H12"
		)
		(pin "H13"
		)
		(pin "H14"
		)
		(pin "H15"
		)
		(pin "H16"
		)
		(pin "J11"
		)
		(pin "J12"
		)
		(pin "J13"
		)
		(pin "J15"
		)
		(pin "J16"
		)
		(pin "K11"
		)
		(pin "K12"
		)
		(pin "L10"
		)
		(pin "L11"
		)
		(pin "L12"
		)
		(pin "M11"
		)
		(pin "M12"
		)
		(pin "M13"
		)
		(pin "M14"
		)
		(pin "M15"
		)
		(pin "M16"
		)
		(pin "N11"
		)
		(pin "N12"
		)
		(pin "N13"
		)
		(pin "N14"
		)
		(pin "N15"
		)
		(pin "N16"
		)
		(pin "P10"
		)
		(pin "P11"
		)
		(pin "P12"
		)
		(pin "P14"
		)
		(pin "P15"
		)
		(pin "P16"
		)
		(pin "R10"
		)
		(pin "R11"
		)
		(pin "R12"
		)
		(pin "R13"
		)
		(pin "R14"
		)
		(pin "R15"
		)
		(pin "R16"
		)
		(pin "T11"
		)
		(pin "T12"
		)
		(pin "T13"
		)
		(pin "T14"
		)
		(pin "T15"
		)
		(pin "L8"
		)
		(pin "L9"
		)
		(pin "M10"
		)
		(pin "M8"
		)
		(pin "M9"
		)
		(pin "N10"
		)
		(pin "N6"
		)
		(pin "N8"
		)
		(pin "N9"
		)
		(pin "P4"
		)
		(pin "P5"
		)
		(pin "P6"
		)
		(pin "P7"
		)
		(pin "P8"
		)
		(pin "P9"
		)
		(pin "R1"
		)
		(pin "R2"
		)
		(pin "R3"
		)
		(pin "R4"
		)
		(pin "R5"
		)
		(pin "R6"
		)
		(pin "R7"
		)
		(pin "R8"
		)
		(pin "R9"
		)
		(pin "T10"
		)
		(pin "T2"
		)
		(pin "T3"
		)
		(pin "T4"
		)
		(pin "T5"
		)
		(pin "T6"
		)
		(pin "T7"
		)
		(pin "T8"
		)
		(pin "T9"
		)
		(pin "K7"
		)
		(pin "L6"
		)
		(pin "L7"
		)
		(pin "M4"
		)
		(pin "M7"
		)
		(pin "N3"
		)
		(pin "N4"
		)
		(pin "N5"
		)
		(pin "P1"
		)
		(pin "P2"
		)
		(pin "P3"
		)
		(pin "H1"
		)
		(pin "H2"
		)
		(pin "H3"
		)
		(pin "H4"
		)
		(pin "H5"
		)
		(pin "H6"
		)
		(pin "J1"
		)
		(pin "J2"
		)
		(pin "J4"
		)
		(pin "J5"
		)
		(pin "J6"
		)
		(pin "K1"
		)
		(pin "K2"
		)
		(pin "K3"
		)
		(pin "K4"
		)
		(pin "K5"
		)
		(pin "K6"
		)
		(pin "L1"
		)
		(pin "L2"
		)
		(pin "L3"
		)
		(pin "L4"
		)
		(pin "L5"
		)
		(pin "M1"
		)
		(pin "M2"
		)
		(pin "M3"
		)
		(pin "N1"
		)
		(pin "N2"
		)
		(pin "D4"
		)
		(pin "D5"
		)
		(pin "D6"
		)
		(pin "E4"
		)
		(pin "E5"
		)
		(pin "E6"
		)
		(pin "F4"
		)
		(pin "F5"
		)
		(pin "F6"
		)
		(pin "G3"
		)
		(pin "G4"
		)
		(pin "G6"
		)
		(pin "B1"
		)
		(pin "B2"
		)
		(pin "C1"
		)
		(pin "C2"
		)
		(pin "D1"
		)
		(pin "D2"
		)
		(pin "E1"
		)
		(pin "E2"
		)
		(pin "F1"
		)
		(pin "F2"
		)
		(pin "A3"
		)
		(pin "A4"
		)
		(pin "A5"
		)
		(pin "A6"
		)
		(pin "A7"
		)
		(pin "B3"
		)
		(pin "B4"
		)
		(pin "B5"
		)
		(pin "B6"
		)
		(pin "B7"
		)
		(pin "K13"
		)
		(pin "K14"
		)
		(pin "K15"
		)
		(pin "K16"
		)
		(pin "L13"
		)
		(pin "L14"
		)
		(pin "L15"
		)
		(pin "L16"
		)
		(pin "A11"
		)
		(pin "A12"
		)
		(pin "A14"
		)
		(pin "A15"
		)
		(pin "A9"
		)
		(pin "B12"
		)
		(pin "B9"
		)
		(pin "C11"
		)
		(pin "A1"
		)
		(pin "A10"
		)
		(pin "A13"
		)
		(pin "A16"
		)
		(pin "A2"
		)
		(pin "A8"
		)
		(pin "B10"
		)
		(pin "B11"
		)
		(pin "B13"
		)
		(pin "B14"
		)
		(pin "B15"
		)
		(pin "B8"
		)
		(pin "C10"
		)
		(pin "C3"
		)
		(pin "C4"
		)
		(pin "C5"
		)
		(pin "C6"
		)
		(pin "C7"
		)
		(pin "C8"
		)
		(pin "C9"
		)
		(pin "D14"
		)
		(pin "D3"
		)
		(pin "D7"
		)
		(pin "D8"
		)
		(pin "D9"
		)
		(pin "E3"
		)
		(pin "E7"
		)
		(pin "E8"
		)
		(pin "F12"
		)
		(pin "F3"
		)
		(pin "F7"
		)
		(pin "F8"
		)
		(pin "G1"
		)
		(pin "G2"
		)
		(pin "G5"
		)
		(pin "G7"
		)
		(pin "G8"
		)
		(pin "H7"
		)
		(pin "H8"
		)
		(pin "H9"
		)
		(pin "J10"
		)
		(pin "J14"
		)
		(pin "J3"
		)
		(pin "J7"
		)
		(pin "J8"
		)
		(pin "J9"
		)
		(pin "K10"
		)
		(pin "K8"
		)
		(pin "K9"
		)
		(pin "M5"
		)
		(pin "M6"
		)
		(pin "N7"
		)
		(pin "P13"
		)
		(pin "T1"
		)
		(pin "T16"
		)
		(instances
			(project "sdi-mipi-video-converter"
				(path ""
					(reference "U11")
					(unit 12)
				)
			)
		)
	)
	(symbol
		(lib_id "antmicroInterfaceDriversReceiversTransceivers:SC18IS602BIPW")
		(at 257.81 134.62 0)
		(unit 1)
		(exclude_from_sim no)
		(in_bom yes)
		(on_board yes)
		(dnp no)
		(fields_autoplaced yes)
		(property "Reference" "U17"
			(at 271.78 127 0)
			(effects
				(font
					(size 1.27 1.27)
					(thickness 0.15)
				)
			)
		)
		(property "Value" "SC18IS602BIPW"
			(at 271.78 129.54 0)
			(effects
				(font
					(size 1.27 1.27)
					(thickness 0.15)
				)
			)
		)
		(property "Footprint" "antmicro-footprints:TSSOP-16_4.4x5mm_P0.65mm"
			(at 311.15 142.24 0)
			(effects
				(font
					(size 1.27 1.27)
					(thickness 0.15)
				)
				(justify left bottom)
				(hide yes)
			)
		)
		(property "Datasheet" "https://www.nxp.com/docs/en/data-sheet/SC18IS602B.pdf"
			(at 311.15 144.78 0)
			(effects
				(font
					(size 1.27 1.27)
					(thickness 0.15)
				)
				(justify left bottom)
				(hide yes)
			)
		)
		(property "Description" "I²C Controller SPI Interface 16-TSSOP"
			(at 257.81 134.62 0)
			(effects
				(font
					(size 1.27 1.27)
				)
				(hide yes)
			)
		)
		(property "Manufacturer" "NXP"
			(at 311.15 147.32 0)
			(effects
				(font
					(size 1.27 1.27)
					(thickness 0.15)
				)
				(justify left bottom)
				(hide yes)
			)
		)
		(property "MPN" "SC18IS602BIPW"
			(at 311.15 149.86 0)
			(effects
				(font
					(size 1.27 1.27)
					(thickness 0.15)
				)
				(justify left bottom)
				(hide yes)
			)
		)
		(property "Author" "Antmicro"
			(at 311.15 152.4 0)
			(effects
				(font
					(size 1.27 1.27)
					(thickness 0.15)
				)
				(justify left bottom)
				(hide yes)
			)
		)
		(property "License" "Apache-2.0"
			(at 311.15 154.94 0)
			(effects
				(font
					(size 1.27 1.27)
					(thickness 0.15)
				)
				(justify left bottom)
				(hide yes)
			)
		)
		(pin "1"
		)
		(pin "10"
		)
		(pin "11"
		)
		(pin "12"
		)
		(pin "13"
		)
		(pin "14"
		)
		(pin "15"
		)
		(pin "16"
		)
		(pin "2"
		)
		(pin "3"
		)
		(pin "4"
		)
		(pin "5"
		)
		(pin "6"
		)
		(pin "7"
		)
		(pin "8"
		)
		(pin "9"
		)
		(instances
			(project "sdi-mipi-video-converter"
				(path ""
					(reference "U17")
					(unit 1)
				)
			)
		)
	)
	(symbol
		(lib_id "antmicroTestPoints:TP_0.75mm_SMD")
		(at 293.37 50.8 90)
		(unit 1)
		(exclude_from_sim no)
		(in_bom yes)
		(on_board yes)
		(dnp no)
		(property "Reference" "TP17"
			(at 293.37 41.275 0)
			(effects
				(font
					(size 1.27 1.27)
					(thickness 0.15)
				)
				(justify right)
			)
		)
		(property "Value" "TP_0.75mm_SMD"
			(at 300.99 33.02 0)
			(effects
				(font
					(size 1.27 1.27)
					(thickness 0.15)
				)
				(justify left bottom)
				(hide yes)
			)
		)
		(property "Footprint" "antmicro-footprints:TP_SMD_0.75mm"
			(at 303.53 33.02 0)
			(effects
				(font
					(size 1.27 1.27)
					(thickness 0.15)
				)
				(justify left bottom)
				(hide yes)
			)
		)
		(property "Datasheet" ""
			(at 306.07 33.02 0)
			(effects
				(font
					(size 1.27 1.27)
					(thickness 0.15)
				)
				(justify left bottom)
				(hide yes)
			)
		)
		(property "Description" "SMT test point"
			(at 293.37 50.8 0)
			(effects
				(font
					(size 1.27 1.27)
				)
				(hide yes)
			)
		)
		(property "MPN" ""
			(at 308.61 33.02 0)
			(effects
				(font
					(size 1.27 1.27)
					(thickness 0.15)
				)
				(justify left bottom)
				(hide yes)
			)
		)
		(property "Manufacturer" ""
			(at 311.15 33.02 0)
			(effects
				(font
					(size 1.27 1.27)
					(thickness 0.15)
				)
				(justify left bottom)
				(hide yes)
			)
		)
		(property "Author" "Antmicro"
			(at 313.69 33.02 0)
			(effects
				(font
					(size 1.27 1.27)
					(thickness 0.15)
				)
				(justify left bottom)
				(hide yes)
			)
		)
		(property "License" "Apache-2.0"
			(at 316.23 33.02 0)
			(effects
				(font
					(size 1.27 1.27)
					(thickness 0.15)
				)
				(justify left bottom)
				(hide yes)
			)
		)
		(pin "1"
		)
		(instances
			(project "sdi-mipi-video-converter"
				(path ""
					(reference "TP17")
					(unit 1)
				)
			)
		)
	)
	(symbol
		(lib_id "antmicroResistors0402:R_10k_0402")
		(at 224.79 207.01 90)
		(unit 1)
		(exclude_from_sim no)
		(in_bom yes)
		(on_board yes)
		(dnp no)
		(fields_autoplaced yes)
		(property "Reference" "R68"
			(at 227.33 203.1999 90)
			(effects
				(font
					(size 1.27 1.27)
					(thickness 0.15)
				)
				(justify right)
			)
		)
		(property "Value" "R_10k_0402"
			(at 237.49 186.69 0)
			(effects
				(font
					(size 1.27 1.27)
					(thickness 0.15)
				)
				(justify left bottom)
				(hide yes)
			)
		)
		(property "Footprint" "antmicro-footprints:R_0402_1005Metric"
			(at 240.03 186.69 0)
			(effects
				(font
					(size 1.27 1.27)
					(thickness 0.15)
				)
				(justify left bottom)
				(hide yes)
			)
		)
		(property "Datasheet" "https://www.bourns.com/docs/product-datasheets/cr.pdf"
			(at 242.57 186.69 0)
			(effects
				(font
					(size 1.27 1.27)
					(thickness 0.15)
				)
				(justify left bottom)
				(hide yes)
			)
		)
		(property "Description" "SMD Chip Resistor, 10 kohm, ± 1%, 62.5 mW, 0402 [1005 Metric], Thick Film, General Purpose"
			(at 224.79 207.01 0)
			(effects
				(font
					(size 1.27 1.27)
				)
				(hide yes)
			)
		)
		(property "Manufacturer" "Bourns"
			(at 247.65 186.69 0)
			(effects
				(font
					(size 1.27 1.27)
					(thickness 0.15)
				)
				(justify left bottom)
				(hide yes)
			)
		)
		(property "MPN" "CR0402-FX-1002GLF"
			(at 245.11 186.69 0)
			(effects
				(font
					(size 1.27 1.27)
					(thickness 0.15)
				)
				(justify left bottom)
				(hide yes)
			)
		)
		(property "Val" "10k"
			(at 227.33 205.7399 90)
			(effects
				(font
					(size 1.27 1.27)
					(thickness 0.15)
				)
				(justify right)
			)
		)
		(property "License" "Apache-2.0"
			(at 250.19 186.69 0)
			(effects
				(font
					(size 1.27 1.27)
					(thickness 0.15)
				)
				(justify left bottom)
				(hide yes)
			)
		)
		(property "Author" "Antmicro"
			(at 252.73 186.69 0)
			(effects
				(font
					(size 1.27 1.27)
					(thickness 0.15)
				)
				(justify left bottom)
				(hide yes)
			)
		)
		(property "Tolerance" "1%"
			(at 234.95 186.69 0)
			(effects
				(font
					(size 1.27 1.27)
				)
				(justify left bottom)
				(hide yes)
			)
		)
		(pin "1"
		)
		(pin "2"
		)
		(instances
			(project "sdi-mipi-video-converter"
				(path ""
					(reference "R68")
					(unit 1)
				)
			)
		)
	)
	(symbol
		(lib_id "antmicropower:GND")
		(at 256.54 165.1 0)
		(unit 1)
		(exclude_from_sim no)
		(in_bom yes)
		(on_board yes)
		(dnp no)
		(fields_autoplaced yes)
		(property "Reference" "#PWR0168"
			(at 265.43 167.64 0)
			(effects
				(font
					(size 1.27 1.27)
					(thickness 0.15)
				)
				(justify left bottom)
				(hide yes)
			)
		)
		(property "Value" "GND"
			(at 256.54 170.18 0)
			(effects
				(font
					(size 1.27 1.27)
					(thickness 0.15)
				)
			)
		)
		(property "Footprint" ""
			(at 265.43 172.72 0)
			(effects
				(font
					(size 1.27 1.27)
					(thickness 0.15)
				)
				(justify left bottom)
				(hide yes)
			)
		)
		(property "Datasheet" ""
			(at 265.43 177.8 0)
			(effects
				(font
					(size 1.27 1.27)
					(thickness 0.15)
				)
				(justify left bottom)
				(hide yes)
			)
		)
		(property "Description" ""
			(at 256.54 165.1 0)
			(effects
				(font
					(size 1.27 1.27)
				)
				(hide yes)
			)
		)
		(property "Author" "Antmicro"
			(at 265.43 172.72 0)
			(effects
				(font
					(size 1.27 1.27)
					(thickness 0.15)
				)
				(justify left bottom)
				(hide yes)
			)
		)
		(property "License" "Apache-2.0"
			(at 265.43 175.26 0)
			(effects
				(font
					(size 1.27 1.27)
					(thickness 0.15)
				)
				(justify left bottom)
				(hide yes)
			)
		)
		(pin "1"
		)
		(instances
			(project "sdi-mipi-video-converter"
				(path ""
					(reference "#PWR0168")
					(unit 1)
				)
			)
		)
	)
	(symbol
		(lib_id "antmicroResistors0402:R_1k_0402")
		(at 243.84 132.08 270)
		(mirror x)
		(unit 1)
		(exclude_from_sim no)
		(in_bom yes)
		(on_board yes)
		(dnp no)
		(fields_autoplaced yes)
		(property "Reference" "R79"
			(at 246.38 128.2699 90)
			(effects
				(font
					(size 1.27 1.27)
					(thickness 0.15)
				)
				(justify left)
			)
		)
		(property "Value" "R_1k_0402"
			(at 231.14 111.76 0)
			(effects
				(font
					(size 1.27 1.27)
					(thickness 0.15)
				)
				(justify left bottom)
				(hide yes)
			)
		)
		(property "Footprint" "antmicro-footprints:R_0402_1005Metric"
			(at 228.6 111.76 0)
			(effects
				(font
					(size 1.27 1.27)
					(thickness 0.15)
				)
				(justify left bottom)
				(hide yes)
			)
		)
		(property "Datasheet" "https://www.bourns.com/docs/product-datasheets/cr.pdf"
			(at 226.06 111.76 0)
			(effects
				(font
					(size 1.27 1.27)
					(thickness 0.15)
				)
				(justify left bottom)
				(hide yes)
			)
		)
		(property "Description" "SMD Chip Resistor, 1 kohm, ± 1%, 63 mW, 0402 [1005 Metric], Thick Film, General Purpose"
			(at 243.84 132.08 0)
			(effects
				(font
					(size 1.27 1.27)
				)
				(hide yes)
			)
		)
		(property "Manufacturer" "Bourns"
			(at 220.98 111.76 0)
			(effects
				(font
					(size 1.27 1.27)
					(thickness 0.15)
				)
				(justify left bottom)
				(hide yes)
			)
		)
		(property "MPN" "CR0402-FX-1001GLF"
			(at 223.52 111.76 0)
			(effects
				(font
					(size 1.27 1.27)
					(thickness 0.15)
				)
				(justify left bottom)
				(hide yes)
			)
		)
		(property "Val" "1k"
			(at 246.38 130.8099 90)
			(effects
				(font
					(size 1.27 1.27)
					(thickness 0.15)
				)
				(justify left)
			)
		)
		(property "License" "Apache-2.0"
			(at 218.44 111.76 0)
			(effects
				(font
					(size 1.27 1.27)
					(thickness 0.15)
				)
				(justify left bottom)
				(hide yes)
			)
		)
		(property "Author" "Antmicro"
			(at 215.9 111.76 0)
			(effects
				(font
					(size 1.27 1.27)
					(thickness 0.15)
				)
				(justify left bottom)
				(hide yes)
			)
		)
		(property "Tolerance" "1%"
			(at 233.68 111.76 0)
			(effects
				(font
					(size 1.27 1.27)
				)
				(justify left bottom)
				(hide yes)
			)
		)
		(pin "1"
		)
		(pin "2"
		)
		(instances
			(project "sdi-mipi-video-converter"
				(path ""
					(reference "R79")
					(unit 1)
				)
			)
		)
	)
	(symbol
		(lib_id "antmicroResistors0402:R_2k2_0402")
		(at 370.84 215.9 90)
		(unit 1)
		(exclude_from_sim no)
		(in_bom yes)
		(on_board yes)
		(dnp no)
		(fields_autoplaced yes)
		(property "Reference" "R93"
			(at 373.38 212.0899 90)
			(effects
				(font
					(size 1.27 1.27)
					(thickness 0.15)
				)
				(justify right)
			)
		)
		(property "Value" "R_2k2_0402"
			(at 383.54 195.58 0)
			(effects
				(font
					(size 1.27 1.27)
					(thickness 0.15)
				)
				(justify left bottom)
				(hide yes)
			)
		)
		(property "Footprint" "antmicro-footprints:R_0402_1005Metric"
			(at 386.08 195.58 0)
			(effects
				(font
					(size 1.27 1.27)
					(thickness 0.15)
				)
				(justify left bottom)
				(hide yes)
			)
		)
		(property "Datasheet" "https://www.bourns.com/docs/product-datasheets/cr.pdf"
			(at 388.62 195.58 0)
			(effects
				(font
					(size 1.27 1.27)
					(thickness 0.15)
				)
				(justify left bottom)
				(hide yes)
			)
		)
		(property "Description" "SMD Chip Resistor, 2.2 kohm, ± 1%, 62.5 mW, 0402 [1005 Metric], Thick Film, General Purpose"
			(at 370.84 215.9 0)
			(effects
				(font
					(size 1.27 1.27)
				)
				(hide yes)
			)
		)
		(property "Manufacturer" "Bourns"
			(at 393.7 195.58 0)
			(effects
				(font
					(size 1.27 1.27)
					(thickness 0.15)
				)
				(justify left bottom)
				(hide yes)
			)
		)
		(property "MPN" "CR0402-FX-2201GLF"
			(at 391.16 195.58 0)
			(effects
				(font
					(size 1.27 1.27)
					(thickness 0.15)
				)
				(justify left bottom)
				(hide yes)
			)
		)
		(property "Val" "2k2"
			(at 373.38 214.6299 90)
			(effects
				(font
					(size 1.27 1.27)
					(thickness 0.15)
				)
				(justify right)
			)
		)
		(property "License" "Apache-2.0"
			(at 396.24 195.58 0)
			(effects
				(font
					(size 1.27 1.27)
					(thickness 0.15)
				)
				(justify left bottom)
				(hide yes)
			)
		)
		(property "Author" "Antmicro"
			(at 398.78 195.58 0)
			(effects
				(font
					(size 1.27 1.27)
					(thickness 0.15)
				)
				(justify left bottom)
				(hide yes)
			)
		)
		(property "Tolerance" "1%"
			(at 381 195.58 0)
			(effects
				(font
					(size 1.27 1.27)
				)
				(justify left bottom)
				(hide yes)
			)
		)
		(pin "1"
		)
		(pin "2"
		)
		(instances
			(project "sdi-mipi-video-converter"
				(path ""
					(reference "R93")
					(unit 1)
				)
			)
		)
	)
	(symbol
		(lib_id "antmicroCapacitors0402:C_100n_0402")
		(at 251.46 163.83 270)
		(mirror x)
		(unit 1)
		(exclude_from_sim no)
		(in_bom yes)
		(on_board yes)
		(dnp no)
		(property "Reference" "C81"
			(at 251.46 159.385 90)
			(effects
				(font
					(size 1.27 1.27)
					(thickness 0.15)
				)
				(justify right)
			)
		)
		(property "Value" "C_100n_0402"
			(at 241.3 143.51 0)
			(effects
				(font
					(size 1.27 1.27)
					(thickness 0.15)
				)
				(justify left bottom)
				(hide yes)
			)
		)
		(property "Footprint" "antmicro-footprints:C_0402_1005Metric"
			(at 238.76 143.51 0)
			(effects
				(font
					(size 1.27 1.27)
					(thickness 0.15)
				)
				(justify left bottom)
				(hide yes)
			)
		)
		(property "Datasheet" "https://www.murata.com/products/productdetail?partno=GRM155R61H104KE14%23"
			(at 236.22 143.51 0)
			(effects
				(font
					(size 1.27 1.27)
					(thickness 0.15)
				)
				(justify left bottom)
				(hide yes)
			)
		)
		(property "Description" "SMD Multilayer Ceramic Capacitor, 0.1 µF, 50 V, 0402 [1005 Metric], ± 10%, X5R, GRM Series"
			(at 251.46 163.83 0)
			(effects
				(font
					(size 1.27 1.27)
				)
				(hide yes)
			)
		)
		(property "Manufacturer" "Murata"
			(at 231.14 143.51 0)
			(effects
				(font
					(size 1.27 1.27)
					(thickness 0.15)
				)
				(justify left bottom)
				(hide yes)
			)
		)
		(property "MPN" "GRM155R61H104KE14D"
			(at 233.68 143.51 0)
			(effects
				(font
					(size 1.27 1.27)
					(thickness 0.15)
				)
				(justify left bottom)
				(hide yes)
			)
		)
		(property "Val" "100n"
			(at 251.46 163.195 90)
			(effects
				(font
					(size 1.27 1.27)
					(thickness 0.15)
				)
				(justify right)
			)
		)
		(property "License" "Apache-2.0"
			(at 228.6 143.51 0)
			(effects
				(font
					(size 1.27 1.27)
					(thickness 0.15)
				)
				(justify left bottom)
				(hide yes)
			)
		)
		(property "Author" "Antmicro"
			(at 226.06 143.51 0)
			(effects
				(font
					(size 1.27 1.27)
					(thickness 0.15)
				)
				(justify left bottom)
				(hide yes)
			)
		)
		(property "Voltage" "50V"
			(at 223.52 143.51 0)
			(effects
				(font
					(size 1.27 1.27)
				)
				(justify left bottom)
				(hide yes)
			)
		)
		(property "Dielectric" "X5R"
			(at 220.98 143.51 0)
			(effects
				(font
					(size 1.27 1.27)
				)
				(justify left bottom)
				(hide yes)
			)
		)
		(pin "1"
		)
		(pin "2"
		)
		(instances
			(project "sdi-mipi-video-converter"
				(path ""
					(reference "C81")
					(unit 1)
				)
			)
		)
	)
	(symbol
		(lib_id "antmicropower:+3.3V")
		(at 336.55 38.1 0)
		(unit 1)
		(exclude_from_sim no)
		(in_bom yes)
		(on_board yes)
		(dnp no)
		(fields_autoplaced yes)
		(property "Reference" "#PWR0179"
			(at 336.55 41.91 0)
			(effects
				(font
					(size 1.27 1.27)
				)
				(hide yes)
			)
		)
		(property "Value" "+3V3"
			(at 334.01 36.8299 0)
			(effects
				(font
					(size 1.27 1.27)
				)
				(justify right)
			)
		)
		(property "Footprint" ""
			(at 336.55 38.1 0)
			(effects
				(font
					(size 1.27 1.27)
				)
				(hide yes)
			)
		)
		(property "Datasheet" ""
			(at 336.55 38.1 0)
			(effects
				(font
					(size 1.27 1.27)
				)
				(hide yes)
			)
		)
		(property "Description" ""
			(at 336.55 38.1 0)
			(effects
				(font
					(size 1.27 1.27)
				)
				(hide yes)
			)
		)
		(pin "1"
		)
		(instances
			(project "sdi-mipi-video-converter"
				(path ""
					(reference "#PWR0179")
					(unit 1)
				)
			)
		)
	)
	(symbol
		(lib_id "antmicroTransistorsFETsMOSFETsSingle:2N7002_SOT-23-3")
		(at 308.61 229.87 0)
		(unit 1)
		(exclude_from_sim no)
		(in_bom yes)
		(on_board yes)
		(dnp no)
		(fields_autoplaced yes)
		(property "Reference" "Q6"
			(at 320.04 226.0599 0)
			(effects
				(font
					(size 1.27 1.27)
					(thickness 0.15)
				)
				(justify left)
			)
		)
		(property "Value" "2N7002_SOT-23-3"
			(at 320.04 228.5999 0)
			(effects
				(font
					(size 1.27 1.27)
					(thickness 0.15)
				)
				(justify left)
			)
		)
		(property "Footprint" "antmicro-footprints:SOT-23-3"
			(at 331.47 240.03 0)
			(effects
				(font
					(size 1.27 1.27)
					(thickness 0.15)
				)
				(justify left bottom)
				(hide yes)
			)
		)
		(property "Datasheet" "https://www.onsemi.com/pub/Collateral/NDS7002A-D.PDF"
			(at 331.47 242.57 0)
			(effects
				(font
					(size 1.27 1.27)
					(thickness 0.15)
				)
				(justify left bottom)
				(hide yes)
			)
		)
		(property "Description" "Power MOSFET, N Channel, 60 V, 115 mA, 1.2 ohm, SOT-23, Surface Mount"
			(at 308.61 229.87 0)
			(effects
				(font
					(size 1.27 1.27)
				)
				(hide yes)
			)
		)
		(property "MPN" "2N7002"
			(at 331.47 245.11 0)
			(effects
				(font
					(size 1.27 1.27)
					(thickness 0.15)
				)
				(justify left bottom)
				(hide yes)
			)
		)
		(property "Manufacturer" "ON Semiconductor"
			(at 331.47 247.65 0)
			(effects
				(font
					(size 1.27 1.27)
					(thickness 0.15)
				)
				(justify left bottom)
				(hide yes)
			)
		)
		(property "Author" "Antmicro"
			(at 331.47 250.19 0)
			(effects
				(font
					(size 1.27 1.27)
					(thickness 0.15)
				)
				(justify left bottom)
				(hide yes)
			)
		)
		(property "License" "Apache-2.0"
			(at 331.47 252.73 0)
			(effects
				(font
					(size 1.27 1.27)
					(thickness 0.15)
				)
				(justify left bottom)
				(hide yes)
			)
		)
		(pin "1"
		)
		(pin "2"
		)
		(pin "3"
		)
		(instances
			(project "sdi-mipi-video-converter"
				(path ""
					(reference "Q6")
					(unit 1)
				)
			)
		)
	)
	(symbol
		(lib_id "antmicroCapacitorsmisc:C_100n_0201")
		(at 142.24 64.77 90)
		(unit 1)
		(exclude_from_sim no)
		(in_bom yes)
		(on_board yes)
		(dnp no)
		(fields_autoplaced yes)
		(property "Reference" "C75"
			(at 144.78 60.9535 90)
			(effects
				(font
					(size 1.27 1.27)
					(thickness 0.15)
				)
				(justify right)
			)
		)
		(property "Value" "C_100n_0201"
			(at 152.4 44.45 0)
			(effects
				(font
					(size 1.27 1.27)
					(thickness 0.15)
				)
				(justify left bottom)
				(hide yes)
			)
		)
		(property "Footprint" "antmicro-footprints:C_0201"
			(at 154.94 44.45 0)
			(effects
				(font
					(size 1.27 1.27)
					(thickness 0.15)
				)
				(justify left bottom)
				(hide yes)
			)
		)
		(property "Datasheet" "https://www.yageo.com/en/Chart/Download/pdf/CC0201KRX6S5BB104"
			(at 157.48 44.45 0)
			(effects
				(font
					(size 1.27 1.27)
					(thickness 0.15)
				)
				(justify left bottom)
				(hide yes)
			)
		)
		(property "Description" "SMD Multilayer Ceramic Capacitor, 0.1 µF, 6.3 V, 0201 [0603 Metric], ± 10%, X6S, CC Series"
			(at 142.24 64.77 0)
			(effects
				(font
					(size 1.27 1.27)
				)
				(hide yes)
			)
		)
		(property "Manufacturer" "YAGEO"
			(at 162.56 44.45 0)
			(effects
				(font
					(size 1.27 1.27)
					(thickness 0.15)
				)
				(justify left bottom)
				(hide yes)
			)
		)
		(property "MPN" "CC0201KRX6S5BB104"
			(at 160.02 44.45 0)
			(effects
				(font
					(size 1.27 1.27)
					(thickness 0.15)
				)
				(justify left bottom)
				(hide yes)
			)
		)
		(property "Val" "100n"
			(at 144.78 63.4935 90)
			(effects
				(font
					(size 1.27 1.27)
					(thickness 0.15)
				)
				(justify right)
			)
		)
		(property "License" "Apache-2.0"
			(at 165.1 44.45 0)
			(effects
				(font
					(size 1.27 1.27)
					(thickness 0.15)
				)
				(justify left bottom)
				(hide yes)
			)
		)
		(property "Author" "Antmicro"
			(at 167.64 44.45 0)
			(effects
				(font
					(size 1.27 1.27)
					(thickness 0.15)
				)
				(justify left bottom)
				(hide yes)
			)
		)
		(property "Voltage" ""
			(at 170.18 44.45 0)
			(effects
				(font
					(size 1.27 1.27)
				)
				(justify left bottom)
				(hide yes)
			)
		)
		(property "Dielectric" ""
			(at 172.72 44.45 0)
			(effects
				(font
					(size 1.27 1.27)
				)
				(justify left bottom)
				(hide yes)
			)
		)
		(property "Public" "False"
			(at 175.26 44.45 0)
			(effects
				(font
					(size 1.27 1.27)
				)
				(justify left bottom)
				(hide yes)
			)
		)
		(pin "1"
		)
		(pin "2"
		)
		(instances
			(project "sdi-mipi-video-converter"
				(path ""
					(reference "C75")
					(unit 1)
				)
			)
		)
	)
	(symbol
		(lib_id "antmicropower:GND")
		(at 142.24 64.77 0)
		(mirror y)
		(unit 1)
		(exclude_from_sim no)
		(in_bom yes)
		(on_board yes)
		(dnp no)
		(fields_autoplaced yes)
		(property "Reference" "#PWR0161"
			(at 133.35 67.31 0)
			(effects
				(font
					(size 1.27 1.27)
					(thickness 0.15)
				)
				(justify left bottom)
				(hide yes)
			)
		)
		(property "Value" "GND"
			(at 142.24 69.85 0)
			(effects
				(font
					(size 1.27 1.27)
					(thickness 0.15)
				)
			)
		)
		(property "Footprint" ""
			(at 133.35 72.39 0)
			(effects
				(font
					(size 1.27 1.27)
					(thickness 0.15)
				)
				(justify left bottom)
				(hide yes)
			)
		)
		(property "Datasheet" ""
			(at 133.35 77.47 0)
			(effects
				(font
					(size 1.27 1.27)
					(thickness 0.15)
				)
				(justify left bottom)
				(hide yes)
			)
		)
		(property "Description" ""
			(at 142.24 64.77 0)
			(effects
				(font
					(size 1.27 1.27)
				)
				(hide yes)
			)
		)
		(property "Author" "Antmicro"
			(at 133.35 72.39 0)
			(effects
				(font
					(size 1.27 1.27)
					(thickness 0.15)
				)
				(justify left bottom)
				(hide yes)
			)
		)
		(property "License" "Apache-2.0"
			(at 133.35 74.93 0)
			(effects
				(font
					(size 1.27 1.27)
					(thickness 0.15)
				)
				(justify left bottom)
				(hide yes)
			)
		)
		(pin "1"
		)
		(instances
			(project "sdi-mipi-video-converter"
				(path ""
					(reference "#PWR0161")
					(unit 1)
				)
			)
		)
	)
	(symbol
		(lib_id "antmicroFPGAChips:CrossLink_LIFCL-40-9BG256C")
		(at 118.11 53.34 0)
		(mirror y)
		(unit 1)
		(exclude_from_sim no)
		(in_bom yes)
		(on_board yes)
		(dnp no)
		(fields_autoplaced yes)
		(property "Reference" "U11"
			(at 95.25 43.18 0)
			(effects
				(font
					(size 1.27 1.27)
					(thickness 0.15)
				)
			)
		)
		(property "Value" "LIFCL-40-9BG256C"
			(at 95.25 45.72 0)
			(effects
				(font
					(size 1.27 1.27)
					(thickness 0.15)
				)
				(hide yes)
			)
		)
		(property "Footprint" "antmicro-footprints:BGA-256_14x14mm_Layout16x16_P0.8mm"
			(at 64.77 60.96 0)
			(effects
				(font
					(size 1.27 1.27)
					(thickness 0.15)
				)
				(justify left bottom)
				(hide yes)
			)
		)
		(property "Datasheet" "https://www.latticesemi.com/-/media/LatticeSemi/Documents/DataSheets/CrossLink/FPGA-DS-02007-2-1-CrossLink-Family-Data-Sheet.ashx?document_id=51662"
			(at 64.77 63.5 0)
			(effects
				(font
					(size 1.27 1.27)
					(thickness 0.15)
				)
				(justify left bottom)
				(hide yes)
			)
		)
		(property "Description" "CrossLink-NX™ Field Programmable Gate Array 256-LFBGA"
			(at 95.25 45.72 0)
			(effects
				(font
					(size 1.27 1.27)
				)
				(hide yes)
			)
		)
		(property "MPN" "LIFCL-40-9BG256C"
			(at 95.25 48.26 0)
			(effects
				(font
					(size 1.27 1.27)
					(thickness 0.15)
				)
			)
		)
		(property "Manufacturer" "Lattice Semiconductor"
			(at 64.77 66.04 0)
			(effects
				(font
					(size 1.27 1.27)
					(thickness 0.15)
				)
				(justify left bottom)
				(hide yes)
			)
		)
		(property "Author" "Antmicro"
			(at 64.77 68.58 0)
			(effects
				(font
					(size 1.27 1.27)
					(thickness 0.15)
				)
				(justify left bottom)
				(hide yes)
			)
		)
		(property "License" "Apache-2.0"
			(at 64.77 71.12 0)
			(effects
				(font
					(size 1.27 1.27)
					(thickness 0.15)
				)
				(justify left bottom)
				(hide yes)
			)
		)
		(pin "B16"
		)
		(pin "C12"
		)
		(pin "C13"
		)
		(pin "C14"
		)
		(pin "C15"
		)
		(pin "C16"
		)
		(pin "D11"
		)
		(pin "D12"
		)
		(pin "D13"
		)
		(pin "D15"
		)
		(pin "D16"
		)
		(pin "E15"
		)
		(pin "E16"
		)
		(pin "D10"
		)
		(pin "E10"
		)
		(pin "E11"
		)
		(pin "E12"
		)
		(pin "E13"
		)
		(pin "E14"
		)
		(pin "E9"
		)
		(pin "F10"
		)
		(pin "F11"
		)
		(pin "F13"
		)
		(pin "F14"
		)
		(pin "F15"
		)
		(pin "F16"
		)
		(pin "F9"
		)
		(pin "G10"
		)
		(pin "G11"
		)
		(pin "G12"
		)
		(pin "G13"
		)
		(pin "G14"
		)
		(pin "G15"
		)
		(pin "G16"
		)
		(pin "G9"
		)
		(pin "H10"
		)
		(pin "H11"
		)
		(pin "H12"
		)
		(pin "H13"
		)
		(pin "H14"
		)
		(pin "H15"
		)
		(pin "H16"
		)
		(pin "J11"
		)
		(pin "J12"
		)
		(pin "J13"
		)
		(pin "J15"
		)
		(pin "J16"
		)
		(pin "K11"
		)
		(pin "K12"
		)
		(pin "L10"
		)
		(pin "L11"
		)
		(pin "L12"
		)
		(pin "M11"
		)
		(pin "M12"
		)
		(pin "M13"
		)
		(pin "M14"
		)
		(pin "M15"
		)
		(pin "M16"
		)
		(pin "N11"
		)
		(pin "N12"
		)
		(pin "N13"
		)
		(pin "N14"
		)
		(pin "N15"
		)
		(pin "N16"
		)
		(pin "P10"
		)
		(pin "P11"
		)
		(pin "P12"
		)
		(pin "P14"
		)
		(pin "P15"
		)
		(pin "P16"
		)
		(pin "R10"
		)
		(pin "R11"
		)
		(pin "R12"
		)
		(pin "R13"
		)
		(pin "R14"
		)
		(pin "R15"
		)
		(pin "R16"
		)
		(pin "T11"
		)
		(pin "T12"
		)
		(pin "T13"
		)
		(pin "T14"
		)
		(pin "T15"
		)
		(pin "L8"
		)
		(pin "L9"
		)
		(pin "M10"
		)
		(pin "M8"
		)
		(pin "M9"
		)
		(pin "N10"
		)
		(pin "N6"
		)
		(pin "N8"
		)
		(pin "N9"
		)
		(pin "P4"
		)
		(pin "P5"
		)
		(pin "P6"
		)
		(pin "P7"
		)
		(pin "P8"
		)
		(pin "P9"
		)
		(pin "R1"
		)
		(pin "R2"
		)
		(pin "R3"
		)
		(pin "R4"
		)
		(pin "R5"
		)
		(pin "R6"
		)
		(pin "R7"
		)
		(pin "R8"
		)
		(pin "R9"
		)
		(pin "T10"
		)
		(pin "T2"
		)
		(pin "T3"
		)
		(pin "T4"
		)
		(pin "T5"
		)
		(pin "T6"
		)
		(pin "T7"
		)
		(pin "T8"
		)
		(pin "T9"
		)
		(pin "K7"
		)
		(pin "L6"
		)
		(pin "L7"
		)
		(pin "M4"
		)
		(pin "M7"
		)
		(pin "N3"
		)
		(pin "N4"
		)
		(pin "N5"
		)
		(pin "P1"
		)
		(pin "P2"
		)
		(pin "P3"
		)
		(pin "H1"
		)
		(pin "H2"
		)
		(pin "H3"
		)
		(pin "H4"
		)
		(pin "H5"
		)
		(pin "H6"
		)
		(pin "J1"
		)
		(pin "J2"
		)
		(pin "J4"
		)
		(pin "J5"
		)
		(pin "J6"
		)
		(pin "K1"
		)
		(pin "K2"
		)
		(pin "K3"
		)
		(pin "K4"
		)
		(pin "K5"
		)
		(pin "K6"
		)
		(pin "L1"
		)
		(pin "L2"
		)
		(pin "L3"
		)
		(pin "L4"
		)
		(pin "L5"
		)
		(pin "M1"
		)
		(pin "M2"
		)
		(pin "M3"
		)
		(pin "N1"
		)
		(pin "N2"
		)
		(pin "D4"
		)
		(pin "D5"
		)
		(pin "D6"
		)
		(pin "E4"
		)
		(pin "E5"
		)
		(pin "E6"
		)
		(pin "F4"
		)
		(pin "F5"
		)
		(pin "F6"
		)
		(pin "G3"
		)
		(pin "G4"
		)
		(pin "G6"
		)
		(pin "B1"
		)
		(pin "B2"
		)
		(pin "C1"
		)
		(pin "C2"
		)
		(pin "D1"
		)
		(pin "D2"
		)
		(pin "E1"
		)
		(pin "E2"
		)
		(pin "F1"
		)
		(pin "F2"
		)
		(pin "A3"
		)
		(pin "A4"
		)
		(pin "A5"
		)
		(pin "A6"
		)
		(pin "A7"
		)
		(pin "B3"
		)
		(pin "B4"
		)
		(pin "B5"
		)
		(pin "B6"
		)
		(pin "B7"
		)
		(pin "K13"
		)
		(pin "K14"
		)
		(pin "K15"
		)
		(pin "K16"
		)
		(pin "L13"
		)
		(pin "L14"
		)
		(pin "L15"
		)
		(pin "L16"
		)
		(pin "A11"
		)
		(pin "A12"
		)
		(pin "A14"
		)
		(pin "A15"
		)
		(pin "A9"
		)
		(pin "B12"
		)
		(pin "B9"
		)
		(pin "C11"
		)
		(pin "A1"
		)
		(pin "A10"
		)
		(pin "A13"
		)
		(pin "A16"
		)
		(pin "A2"
		)
		(pin "A8"
		)
		(pin "B10"
		)
		(pin "B11"
		)
		(pin "B13"
		)
		(pin "B14"
		)
		(pin "B15"
		)
		(pin "B8"
		)
		(pin "C10"
		)
		(pin "C3"
		)
		(pin "C4"
		)
		(pin "C5"
		)
		(pin "C6"
		)
		(pin "C7"
		)
		(pin "C8"
		)
		(pin "C9"
		)
		(pin "D14"
		)
		(pin "D3"
		)
		(pin "D7"
		)
		(pin "D8"
		)
		(pin "D9"
		)
		(pin "E3"
		)
		(pin "E7"
		)
		(pin "E8"
		)
		(pin "F12"
		)
		(pin "F3"
		)
		(pin "F7"
		)
		(pin "F8"
		)
		(pin "G1"
		)
		(pin "G2"
		)
		(pin "G5"
		)
		(pin "G7"
		)
		(pin "G8"
		)
		(pin "H7"
		)
		(pin "H8"
		)
		(pin "H9"
		)
		(pin "J10"
		)
		(pin "J14"
		)
		(pin "J3"
		)
		(pin "J7"
		)
		(pin "J8"
		)
		(pin "J9"
		)
		(pin "K10"
		)
		(pin "K8"
		)
		(pin "K9"
		)
		(pin "M5"
		)
		(pin "M6"
		)
		(pin "N7"
		)
		(pin "P13"
		)
		(pin "T1"
		)
		(pin "T16"
		)
		(instances
			(project "sdi-mipi-video-converter"
				(path ""
					(reference "U11")
					(unit 1)
				)
			)
		)
	)
	(symbol
		(lib_id "antmicroResistors0402:R_4k7_0402")
		(at 317.5 46.99 90)
		(unit 1)
		(exclude_from_sim no)
		(in_bom yes)
		(on_board yes)
		(dnp no)
		(property "Reference" "R87"
			(at 318.77 43.18 90)
			(effects
				(font
					(size 1.27 1.27)
					(thickness 0.15)
				)
				(justify right)
			)
		)
		(property "Value" "R_4k7_0402"
			(at 330.2 26.67 0)
			(effects
				(font
					(size 1.27 1.27)
					(thickness 0.15)
				)
				(justify left bottom)
				(hide yes)
			)
		)
		(property "Footprint" "antmicro-footprints:R_0402_1005Metric"
			(at 332.74 26.67 0)
			(effects
				(font
					(size 1.27 1.27)
					(thickness 0.15)
				)
				(justify left bottom)
				(hide yes)
			)
		)
		(property "Datasheet" "https://www.bourns.com/docs/product-datasheets/cr.pdf"
			(at 335.28 26.67 0)
			(effects
				(font
					(size 1.27 1.27)
					(thickness 0.15)
				)
				(justify left bottom)
				(hide yes)
			)
		)
		(property "Description" "SMD Chip Resistor, 4.7 kohm, ± 1%, 62.5 mW, 0402 [1005 Metric], Thick Film, General Purpose"
			(at 317.5 46.99 0)
			(effects
				(font
					(size 1.27 1.27)
				)
				(hide yes)
			)
		)
		(property "Manufacturer" "Bourns"
			(at 340.36 26.67 0)
			(effects
				(font
					(size 1.27 1.27)
					(thickness 0.15)
				)
				(justify left bottom)
				(hide yes)
			)
		)
		(property "MPN" "CR0402-FX-4701GLF"
			(at 337.82 26.67 0)
			(effects
				(font
					(size 1.27 1.27)
					(thickness 0.15)
				)
				(justify left bottom)
				(hide yes)
			)
		)
		(property "Val" "4k7"
			(at 318.77 45.72 90)
			(effects
				(font
					(size 1.27 1.27)
					(thickness 0.15)
				)
				(justify right)
			)
		)
		(property "License" "Apache-2.0"
			(at 342.9 26.67 0)
			(effects
				(font
					(size 1.27 1.27)
					(thickness 0.15)
				)
				(justify left bottom)
				(hide yes)
			)
		)
		(property "Author" "Antmicro"
			(at 345.44 26.67 0)
			(effects
				(font
					(size 1.27 1.27)
					(thickness 0.15)
				)
				(justify left bottom)
				(hide yes)
			)
		)
		(property "Tolerance" "1%"
			(at 327.66 26.67 0)
			(effects
				(font
					(size 1.27 1.27)
				)
				(justify left bottom)
				(hide yes)
			)
		)
		(pin "1"
		)
		(pin "2"
		)
		(instances
			(project "sdi-mipi-video-converter"
				(path ""
					(reference "R87")
					(unit 1)
				)
			)
		)
	)
	(symbol
		(lib_id "antmicropower:+3.3V")
		(at 142.24 50.8 0)
		(mirror y)
		(unit 1)
		(exclude_from_sim no)
		(in_bom yes)
		(on_board yes)
		(dnp no)
		(fields_autoplaced yes)
		(property "Reference" "#PWR0160"
			(at 142.24 54.61 0)
			(effects
				(font
					(size 1.27 1.27)
				)
				(hide yes)
			)
		)
		(property "Value" "+3V3"
			(at 142.24 45.72 0)
			(effects
				(font
					(size 1.27 1.27)
				)
			)
		)
		(property "Footprint" ""
			(at 142.24 50.8 0)
			(effects
				(font
					(size 1.27 1.27)
				)
				(hide yes)
			)
		)
		(property "Datasheet" ""
			(at 142.24 50.8 0)
			(effects
				(font
					(size 1.27 1.27)
				)
				(hide yes)
			)
		)
		(property "Description" ""
			(at 142.24 50.8 0)
			(effects
				(font
					(size 1.27 1.27)
				)
				(hide yes)
			)
		)
		(pin "1"
		)
		(instances
			(project "sdi-mipi-video-converter"
				(path ""
					(reference "#PWR0160")
					(unit 1)
				)
			)
		)
	)
	(symbol
		(lib_id "antmicroResistors0402:R_0R_0402")
		(at 233.68 158.75 90)
		(mirror x)
		(unit 1)
		(exclude_from_sim no)
		(in_bom yes)
		(on_board yes)
		(dnp no)
		(property "Reference" "R80"
			(at 234.95 160.02 90)
			(effects
				(font
					(size 1.27 1.27)
					(thickness 0.15)
				)
				(justify right)
			)
		)
		(property "Value" "R_0R_0402"
			(at 246.38 179.07 0)
			(effects
				(font
					(size 1.27 1.27)
					(thickness 0.15)
				)
				(justify left bottom)
				(hide yes)
			)
		)
		(property "Footprint" "antmicro-footprints:R_0402_1005Metric"
			(at 248.92 179.07 0)
			(effects
				(font
					(size 1.27 1.27)
					(thickness 0.15)
				)
				(justify left bottom)
				(hide yes)
			)
		)
		(property "Datasheet" "https://industrial.panasonic.com/cdbs/www-data/pdf/RDA0000/AOA0000C301.pdf"
			(at 251.46 179.07 0)
			(effects
				(font
					(size 1.27 1.27)
					(thickness 0.15)
				)
				(justify left bottom)
				(hide yes)
			)
		)
		(property "Description" "SMD Chip Resistor, Jumper, 0 ohm, 100 mW, 0402 [1005 Metric], Thick Film, General Purpose"
			(at 233.68 158.75 0)
			(effects
				(font
					(size 1.27 1.27)
				)
				(hide yes)
			)
		)
		(property "Manufacturer" "Panasonic"
			(at 256.54 179.07 0)
			(effects
				(font
					(size 1.27 1.27)
					(thickness 0.15)
				)
				(justify left bottom)
				(hide yes)
			)
		)
		(property "MPN" "ERJ2GE0R00X"
			(at 254 179.07 0)
			(effects
				(font
					(size 1.27 1.27)
					(thickness 0.15)
				)
				(justify left bottom)
				(hide yes)
			)
		)
		(property "Val" "0R"
			(at 234.95 162.56 90)
			(effects
				(font
					(size 1.27 1.27)
					(thickness 0.15)
				)
				(justify right)
			)
		)
		(property "License" "Apache-2.0"
			(at 259.08 179.07 0)
			(effects
				(font
					(size 1.27 1.27)
					(thickness 0.15)
				)
				(justify left bottom)
				(hide yes)
			)
		)
		(property "Author" "Antmicro"
			(at 261.62 179.07 0)
			(effects
				(font
					(size 1.27 1.27)
					(thickness 0.15)
				)
				(justify left bottom)
				(hide yes)
			)
		)
		(property "Tolerance" "~"
			(at 243.84 179.07 0)
			(effects
				(font
					(size 1.27 1.27)
				)
				(justify left bottom)
				(hide yes)
			)
		)
		(property "Current" "1A"
			(at 264.16 179.07 0)
			(effects
				(font
					(size 1.27 1.27)
					(thickness 0.15)
				)
				(justify left bottom)
				(hide yes)
			)
		)
		(pin "1"
		)
		(pin "2"
		)
		(instances
			(project "sdi-mipi-video-converter"
				(path ""
					(reference "R80")
					(unit 1)
				)
			)
		)
	)
	(symbol
		(lib_id "antmicroResistors0402:R_0R_0402")
		(at 293.37 157.48 0)
		(mirror x)
		(unit 1)
		(exclude_from_sim no)
		(in_bom yes)
		(on_board yes)
		(dnp no)
		(property "Reference" "R142"
			(at 290.83 158.75 0)
			(effects
				(font
					(size 1.27 1.27)
					(thickness 0.15)
				)
			)
		)
		(property "Value" "R_0R_0402"
			(at 313.69 144.78 0)
			(effects
				(font
					(size 1.27 1.27)
					(thickness 0.15)
				)
				(justify left bottom)
				(hide yes)
			)
		)
		(property "Footprint" "antmicro-footprints:R_0402_1005Metric"
			(at 313.69 142.24 0)
			(effects
				(font
					(size 1.27 1.27)
					(thickness 0.15)
				)
				(justify left bottom)
				(hide yes)
			)
		)
		(property "Datasheet" "https://industrial.panasonic.com/cdbs/www-data/pdf/RDA0000/AOA0000C301.pdf"
			(at 313.69 139.7 0)
			(effects
				(font
					(size 1.27 1.27)
					(thickness 0.15)
				)
				(justify left bottom)
				(hide yes)
			)
		)
		(property "Description" "SMD Chip Resistor, Jumper, 0 ohm, 100 mW, 0402 [1005 Metric], Thick Film, General Purpose"
			(at 293.37 157.48 0)
			(effects
				(font
					(size 1.27 1.27)
				)
				(hide yes)
			)
		)
		(property "Manufacturer" "Panasonic"
			(at 313.69 134.62 0)
			(effects
				(font
					(size 1.27 1.27)
					(thickness 0.15)
				)
				(justify left bottom)
				(hide yes)
			)
		)
		(property "MPN" "ERJ2GE0R00X"
			(at 313.69 137.16 0)
			(effects
				(font
					(size 1.27 1.27)
					(thickness 0.15)
				)
				(justify left bottom)
				(hide yes)
			)
		)
		(property "Val" "0R"
			(at 299.72 158.75 0)
			(effects
				(font
					(size 1.27 1.27)
					(thickness 0.15)
				)
			)
		)
		(property "License" "Apache-2.0"
			(at 313.69 132.08 0)
			(effects
				(font
					(size 1.27 1.27)
					(thickness 0.15)
				)
				(justify left bottom)
				(hide yes)
			)
		)
		(property "Author" "Antmicro"
			(at 313.69 129.54 0)
			(effects
				(font
					(size 1.27 1.27)
					(thickness 0.15)
				)
				(justify left bottom)
				(hide yes)
			)
		)
		(property "Tolerance" "~"
			(at 313.69 147.32 0)
			(effects
				(font
					(size 1.27 1.27)
				)
				(justify left bottom)
				(hide yes)
			)
		)
		(property "Current" "1A"
			(at 313.69 127 0)
			(effects
				(font
					(size 1.27 1.27)
					(thickness 0.15)
				)
				(justify left bottom)
				(hide yes)
			)
		)
		(pin "1"
		)
		(pin "2"
		)
		(instances
			(project "sdi-mipi-video-converter"
				(path ""
					(reference "R142")
					(unit 1)
				)
			)
		)
	)
	(symbol
		(lib_id "antmicropower:GND")
		(at 226.06 165.1 0)
		(mirror y)
		(unit 1)
		(exclude_from_sim no)
		(in_bom yes)
		(on_board yes)
		(dnp no)
		(fields_autoplaced yes)
		(property "Reference" "#PWR0176"
			(at 217.17 167.64 0)
			(effects
				(font
					(size 1.27 1.27)
					(thickness 0.15)
				)
				(justify left bottom)
				(hide yes)
			)
		)
		(property "Value" "GND"
			(at 226.06 170.18 0)
			(effects
				(font
					(size 1.27 1.27)
					(thickness 0.15)
				)
			)
		)
		(property "Footprint" ""
			(at 217.17 172.72 0)
			(effects
				(font
					(size 1.27 1.27)
					(thickness 0.15)
				)
				(justify left bottom)
				(hide yes)
			)
		)
		(property "Datasheet" ""
			(at 217.17 177.8 0)
			(effects
				(font
					(size 1.27 1.27)
					(thickness 0.15)
				)
				(justify left bottom)
				(hide yes)
			)
		)
		(property "Description" ""
			(at 226.06 165.1 0)
			(effects
				(font
					(size 1.27 1.27)
				)
				(hide yes)
			)
		)
		(property "Author" "Antmicro"
			(at 217.17 172.72 0)
			(effects
				(font
					(size 1.27 1.27)
					(thickness 0.15)
				)
				(justify left bottom)
				(hide yes)
			)
		)
		(property "License" "Apache-2.0"
			(at 217.17 175.26 0)
			(effects
				(font
					(size 1.27 1.27)
					(thickness 0.15)
				)
				(justify left bottom)
				(hide yes)
			)
		)
		(pin "1"
		)
		(instances
			(project "sdi-mipi-video-converter"
				(path ""
					(reference "#PWR0176")
					(unit 1)
				)
			)
		)
	)
	(symbol
		(lib_id "antmicroResistors0402:R_10k_0402")
		(at 293.37 219.71 90)
		(unit 1)
		(exclude_from_sim no)
		(in_bom yes)
		(on_board yes)
		(dnp no)
		(fields_autoplaced yes)
		(property "Reference" "R81"
			(at 295.91 215.8999 90)
			(effects
				(font
					(size 1.27 1.27)
					(thickness 0.15)
				)
				(justify right)
			)
		)
		(property "Value" "R_10k_0402"
			(at 306.07 199.39 0)
			(effects
				(font
					(size 1.27 1.27)
					(thickness 0.15)
				)
				(justify left bottom)
				(hide yes)
			)
		)
		(property "Footprint" "antmicro-footprints:R_0402_1005Metric"
			(at 308.61 199.39 0)
			(effects
				(font
					(size 1.27 1.27)
					(thickness 0.15)
				)
				(justify left bottom)
				(hide yes)
			)
		)
		(property "Datasheet" "https://www.bourns.com/docs/product-datasheets/cr.pdf"
			(at 311.15 199.39 0)
			(effects
				(font
					(size 1.27 1.27)
					(thickness 0.15)
				)
				(justify left bottom)
				(hide yes)
			)
		)
		(property "Description" "SMD Chip Resistor, 10 kohm, ± 1%, 62.5 mW, 0402 [1005 Metric], Thick Film, General Purpose"
			(at 293.37 219.71 0)
			(effects
				(font
					(size 1.27 1.27)
				)
				(hide yes)
			)
		)
		(property "Manufacturer" "Bourns"
			(at 316.23 199.39 0)
			(effects
				(font
					(size 1.27 1.27)
					(thickness 0.15)
				)
				(justify left bottom)
				(hide yes)
			)
		)
		(property "MPN" "CR0402-FX-1002GLF"
			(at 313.69 199.39 0)
			(effects
				(font
					(size 1.27 1.27)
					(thickness 0.15)
				)
				(justify left bottom)
				(hide yes)
			)
		)
		(property "Val" "10k"
			(at 295.91 218.4399 90)
			(effects
				(font
					(size 1.27 1.27)
					(thickness 0.15)
				)
				(justify right)
			)
		)
		(property "License" "Apache-2.0"
			(at 318.77 199.39 0)
			(effects
				(font
					(size 1.27 1.27)
					(thickness 0.15)
				)
				(justify left bottom)
				(hide yes)
			)
		)
		(property "Author" "Antmicro"
			(at 321.31 199.39 0)
			(effects
				(font
					(size 1.27 1.27)
					(thickness 0.15)
				)
				(justify left bottom)
				(hide yes)
			)
		)
		(property "Tolerance" "1%"
			(at 303.53 199.39 0)
			(effects
				(font
					(size 1.27 1.27)
				)
				(justify left bottom)
				(hide yes)
			)
		)
		(pin "1"
		)
		(pin "2"
		)
		(instances
			(project "sdi-mipi-video-converter"
				(path ""
					(reference "R81")
					(unit 1)
				)
			)
		)
	)
	(symbol
		(lib_id "antmicroResistors0402:R_0R_0402")
		(at 360.68 236.22 0)
		(unit 1)
		(exclude_from_sim no)
		(in_bom yes)
		(on_board yes)
		(dnp no)
		(property "Reference" "R86"
			(at 363.22 232.41 0)
			(effects
				(font
					(size 1.27 1.27)
					(thickness 0.15)
				)
			)
		)
		(property "Value" "R_0R_0402"
			(at 381 248.92 0)
			(effects
				(font
					(size 1.27 1.27)
					(thickness 0.15)
				)
				(justify left bottom)
				(hide yes)
			)
		)
		(property "Footprint" "antmicro-footprints:R_0402_1005Metric"
			(at 381 251.46 0)
			(effects
				(font
					(size 1.27 1.27)
					(thickness 0.15)
				)
				(justify left bottom)
				(hide yes)
			)
		)
		(property "Datasheet" "https://industrial.panasonic.com/cdbs/www-data/pdf/RDA0000/AOA0000C301.pdf"
			(at 381 254 0)
			(effects
				(font
					(size 1.27 1.27)
					(thickness 0.15)
				)
				(justify left bottom)
				(hide yes)
			)
		)
		(property "Description" "SMD Chip Resistor, Jumper, 0 ohm, 100 mW, 0402 [1005 Metric], Thick Film, General Purpose"
			(at 360.68 236.22 0)
			(effects
				(font
					(size 1.27 1.27)
				)
				(hide yes)
			)
		)
		(property "Manufacturer" "Panasonic"
			(at 381 259.08 0)
			(effects
				(font
					(size 1.27 1.27)
					(thickness 0.15)
				)
				(justify left bottom)
				(hide yes)
			)
		)
		(property "MPN" "ERJ2GE0R00X"
			(at 381 256.54 0)
			(effects
				(font
					(size 1.27 1.27)
					(thickness 0.15)
				)
				(justify left bottom)
				(hide yes)
			)
		)
		(property "Val" "0R"
			(at 363.22 234.315 0)
			(effects
				(font
					(size 1.27 1.27)
					(thickness 0.15)
				)
			)
		)
		(property "License" "Apache-2.0"
			(at 381 261.62 0)
			(effects
				(font
					(size 1.27 1.27)
					(thickness 0.15)
				)
				(justify left bottom)
				(hide yes)
			)
		)
		(property "Author" "Antmicro"
			(at 381 264.16 0)
			(effects
				(font
					(size 1.27 1.27)
					(thickness 0.15)
				)
				(justify left bottom)
				(hide yes)
			)
		)
		(property "Tolerance" "~"
			(at 381 246.38 0)
			(effects
				(font
					(size 1.27 1.27)
				)
				(justify left bottom)
				(hide yes)
			)
		)
		(property "Current" "1A"
			(at 381 266.7 0)
			(effects
				(font
					(size 1.27 1.27)
					(thickness 0.15)
				)
				(justify left bottom)
				(hide yes)
			)
		)
		(pin "1"
		)
		(pin "2"
		)
		(instances
			(project "sdi-mipi-video-converter"
				(path ""
					(reference "R86")
					(unit 1)
				)
			)
		)
	)
	(symbol
		(lib_id "antmicroResistors0402:R_0R_0402")
		(at 370.84 125.73 0)
		(unit 1)
		(exclude_from_sim no)
		(in_bom yes)
		(on_board yes)
		(dnp no)
		(property "Reference" "R96"
			(at 368.935 124.46 0)
			(effects
				(font
					(size 1.27 1.27)
					(thickness 0.15)
				)
			)
		)
		(property "Value" "R_0R_0402"
			(at 391.16 138.43 0)
			(effects
				(font
					(size 1.27 1.27)
					(thickness 0.15)
				)
				(justify left bottom)
				(hide yes)
			)
		)
		(property "Footprint" "antmicro-footprints:R_0402_1005Metric"
			(at 391.16 140.97 0)
			(effects
				(font
					(size 1.27 1.27)
					(thickness 0.15)
				)
				(justify left bottom)
				(hide yes)
			)
		)
		(property "Datasheet" "https://industrial.panasonic.com/cdbs/www-data/pdf/RDA0000/AOA0000C301.pdf"
			(at 391.16 143.51 0)
			(effects
				(font
					(size 1.27 1.27)
					(thickness 0.15)
				)
				(justify left bottom)
				(hide yes)
			)
		)
		(property "Description" "SMD Chip Resistor, Jumper, 0 ohm, 100 mW, 0402 [1005 Metric], Thick Film, General Purpose"
			(at 370.84 125.73 0)
			(effects
				(font
					(size 1.27 1.27)
				)
				(hide yes)
			)
		)
		(property "Manufacturer" "Panasonic"
			(at 391.16 148.59 0)
			(effects
				(font
					(size 1.27 1.27)
					(thickness 0.15)
				)
				(justify left bottom)
				(hide yes)
			)
		)
		(property "MPN" "ERJ2GE0R00X"
			(at 391.16 146.05 0)
			(effects
				(font
					(size 1.27 1.27)
					(thickness 0.15)
				)
				(justify left bottom)
				(hide yes)
			)
		)
		(property "Val" "0R"
			(at 377.19 124.46 0)
			(effects
				(font
					(size 1.27 1.27)
					(thickness 0.15)
				)
			)
		)
		(property "License" "Apache-2.0"
			(at 391.16 151.13 0)
			(effects
				(font
					(size 1.27 1.27)
					(thickness 0.15)
				)
				(justify left bottom)
				(hide yes)
			)
		)
		(property "Author" "Antmicro"
			(at 391.16 153.67 0)
			(effects
				(font
					(size 1.27 1.27)
					(thickness 0.15)
				)
				(justify left bottom)
				(hide yes)
			)
		)
		(property "Tolerance" "~"
			(at 391.16 135.89 0)
			(effects
				(font
					(size 1.27 1.27)
				)
				(justify left bottom)
				(hide yes)
			)
		)
		(property "Current" "1A"
			(at 391.16 156.21 0)
			(effects
				(font
					(size 1.27 1.27)
					(thickness 0.15)
				)
				(justify left bottom)
				(hide yes)
			)
		)
		(pin "1"
		)
		(pin "2"
		)
		(instances
			(project "sdi-mipi-video-converter"
				(path ""
					(reference "R96")
					(unit 1)
				)
			)
		)
	)
	(symbol
		(lib_id "antmicroResistors0402:R_0R_0402")
		(at 284.48 82.55 180)
		(unit 1)
		(exclude_from_sim no)
		(in_bom yes)
		(on_board yes)
		(dnp no)
		(property "Reference" "R75"
			(at 277.495 83.82 0)
			(effects
				(font
					(size 1.27 1.27)
					(thickness 0.15)
				)
			)
		)
		(property "Value" "R_0R_0402"
			(at 264.16 69.85 0)
			(effects
				(font
					(size 1.27 1.27)
					(thickness 0.15)
				)
				(justify left bottom)
				(hide yes)
			)
		)
		(property "Footprint" "antmicro-footprints:R_0402_1005Metric"
			(at 264.16 67.31 0)
			(effects
				(font
					(size 1.27 1.27)
					(thickness 0.15)
				)
				(justify left bottom)
				(hide yes)
			)
		)
		(property "Datasheet" "https://industrial.panasonic.com/cdbs/www-data/pdf/RDA0000/AOA0000C301.pdf"
			(at 264.16 64.77 0)
			(effects
				(font
					(size 1.27 1.27)
					(thickness 0.15)
				)
				(justify left bottom)
				(hide yes)
			)
		)
		(property "Description" "SMD Chip Resistor, Jumper, 0 ohm, 100 mW, 0402 [1005 Metric], Thick Film, General Purpose"
			(at 284.48 82.55 0)
			(effects
				(font
					(size 1.27 1.27)
				)
				(hide yes)
			)
		)
		(property "Manufacturer" "Panasonic"
			(at 264.16 59.69 0)
			(effects
				(font
					(size 1.27 1.27)
					(thickness 0.15)
				)
				(justify left bottom)
				(hide yes)
			)
		)
		(property "MPN" "ERJ2GE0R00X"
			(at 264.16 62.23 0)
			(effects
				(font
					(size 1.27 1.27)
					(thickness 0.15)
				)
				(justify left bottom)
				(hide yes)
			)
		)
		(property "Val" "0R"
			(at 285.75 83.82 0)
			(effects
				(font
					(size 1.27 1.27)
					(thickness 0.15)
				)
			)
		)
		(property "License" "Apache-2.0"
			(at 264.16 57.15 0)
			(effects
				(font
					(size 1.27 1.27)
					(thickness 0.15)
				)
				(justify left bottom)
				(hide yes)
			)
		)
		(property "Author" "Antmicro"
			(at 264.16 54.61 0)
			(effects
				(font
					(size 1.27 1.27)
					(thickness 0.15)
				)
				(justify left bottom)
				(hide yes)
			)
		)
		(property "Tolerance" "~"
			(at 264.16 72.39 0)
			(effects
				(font
					(size 1.27 1.27)
				)
				(justify left bottom)
				(hide yes)
			)
		)
		(property "Current" "1A"
			(at 264.16 52.07 0)
			(effects
				(font
					(size 1.27 1.27)
					(thickness 0.15)
				)
				(justify left bottom)
				(hide yes)
			)
		)
		(pin "1"
		)
		(pin "2"
		)
		(instances
			(project "sdi-mipi-video-converter"
				(path ""
					(reference "R75")
					(unit 1)
				)
			)
		)
	)
	(symbol
		(lib_id "antmicroResistors0402:R_0R_0402")
		(at 312.42 66.04 0)
		(unit 1)
		(exclude_from_sim no)
		(in_bom yes)
		(on_board yes)
		(dnp no)
		(fields_autoplaced yes)
		(property "Reference" "R82"
			(at 314.96 69.85 0)
			(effects
				(font
					(size 1.27 1.27)
					(thickness 0.15)
				)
			)
		)
		(property "Value" "R_0R_0402"
			(at 332.74 78.74 0)
			(effects
				(font
					(size 1.27 1.27)
					(thickness 0.15)
				)
				(justify left bottom)
				(hide yes)
			)
		)
		(property "Footprint" "antmicro-footprints:R_0402_1005Metric"
			(at 332.74 81.28 0)
			(effects
				(font
					(size 1.27 1.27)
					(thickness 0.15)
				)
				(justify left bottom)
				(hide yes)
			)
		)
		(property "Datasheet" "https://industrial.panasonic.com/cdbs/www-data/pdf/RDA0000/AOA0000C301.pdf"
			(at 332.74 83.82 0)
			(effects
				(font
					(size 1.27 1.27)
					(thickness 0.15)
				)
				(justify left bottom)
				(hide yes)
			)
		)
		(property "Description" "SMD Chip Resistor, Jumper, 0 ohm, 100 mW, 0402 [1005 Metric], Thick Film, General Purpose"
			(at 312.42 66.04 0)
			(effects
				(font
					(size 1.27 1.27)
				)
				(hide yes)
			)
		)
		(property "Manufacturer" "Panasonic"
			(at 332.74 88.9 0)
			(effects
				(font
					(size 1.27 1.27)
					(thickness 0.15)
				)
				(justify left bottom)
				(hide yes)
			)
		)
		(property "MPN" "ERJ2GE0R00X"
			(at 332.74 86.36 0)
			(effects
				(font
					(size 1.27 1.27)
					(thickness 0.15)
				)
				(justify left bottom)
				(hide yes)
			)
		)
		(property "Val" "0R"
			(at 314.96 72.39 0)
			(effects
				(font
					(size 1.27 1.27)
					(thickness 0.15)
				)
			)
		)
		(property "License" "Apache-2.0"
			(at 332.74 91.44 0)
			(effects
				(font
					(size 1.27 1.27)
					(thickness 0.15)
				)
				(justify left bottom)
				(hide yes)
			)
		)
		(property "Author" "Antmicro"
			(at 332.74 93.98 0)
			(effects
				(font
					(size 1.27 1.27)
					(thickness 0.15)
				)
				(justify left bottom)
				(hide yes)
			)
		)
		(property "Tolerance" "~"
			(at 332.74 76.2 0)
			(effects
				(font
					(size 1.27 1.27)
				)
				(justify left bottom)
				(hide yes)
			)
		)
		(property "Current" "1A"
			(at 332.74 96.52 0)
			(effects
				(font
					(size 1.27 1.27)
					(thickness 0.15)
				)
				(justify left bottom)
				(hide yes)
			)
		)
		(pin "1"
		)
		(pin "2"
		)
		(instances
			(project "sdi-mipi-video-converter"
				(path ""
					(reference "R82")
					(unit 1)
				)
			)
		)
	)
	(symbol
		(lib_id "antmicroResistors0402:R_0R_0402")
		(at 370.84 120.65 0)
		(unit 1)
		(exclude_from_sim no)
		(in_bom yes)
		(on_board yes)
		(dnp no)
		(property "Reference" "R95"
			(at 368.935 119.38 0)
			(effects
				(font
					(size 1.27 1.27)
					(thickness 0.15)
				)
			)
		)
		(property "Value" "R_0R_0402"
			(at 391.16 133.35 0)
			(effects
				(font
					(size 1.27 1.27)
					(thickness 0.15)
				)
				(justify left bottom)
				(hide yes)
			)
		)
		(property "Footprint" "antmicro-footprints:R_0402_1005Metric"
			(at 391.16 135.89 0)
			(effects
				(font
					(size 1.27 1.27)
					(thickness 0.15)
				)
				(justify left bottom)
				(hide yes)
			)
		)
		(property "Datasheet" "https://industrial.panasonic.com/cdbs/www-data/pdf/RDA0000/AOA0000C301.pdf"
			(at 391.16 138.43 0)
			(effects
				(font
					(size 1.27 1.27)
					(thickness 0.15)
				)
				(justify left bottom)
				(hide yes)
			)
		)
		(property "Description" "SMD Chip Resistor, Jumper, 0 ohm, 100 mW, 0402 [1005 Metric], Thick Film, General Purpose"
			(at 370.84 120.65 0)
			(effects
				(font
					(size 1.27 1.27)
				)
				(hide yes)
			)
		)
		(property "Manufacturer" "Panasonic"
			(at 391.16 143.51 0)
			(effects
				(font
					(size 1.27 1.27)
					(thickness 0.15)
				)
				(justify left bottom)
				(hide yes)
			)
		)
		(property "MPN" "ERJ2GE0R00X"
			(at 391.16 140.97 0)
			(effects
				(font
					(size 1.27 1.27)
					(thickness 0.15)
				)
				(justify left bottom)
				(hide yes)
			)
		)
		(property "Val" "0R"
			(at 377.19 119.38 0)
			(effects
				(font
					(size 1.27 1.27)
					(thickness 0.15)
				)
			)
		)
		(property "License" "Apache-2.0"
			(at 391.16 146.05 0)
			(effects
				(font
					(size 1.27 1.27)
					(thickness 0.15)
				)
				(justify left bottom)
				(hide yes)
			)
		)
		(property "Author" "Antmicro"
			(at 391.16 148.59 0)
			(effects
				(font
					(size 1.27 1.27)
					(thickness 0.15)
				)
				(justify left bottom)
				(hide yes)
			)
		)
		(property "Tolerance" "~"
			(at 391.16 130.81 0)
			(effects
				(font
					(size 1.27 1.27)
				)
				(justify left bottom)
				(hide yes)
			)
		)
		(property "Current" "1A"
			(at 391.16 151.13 0)
			(effects
				(font
					(size 1.27 1.27)
					(thickness 0.15)
				)
				(justify left bottom)
				(hide yes)
			)
		)
		(pin "1"
		)
		(pin "2"
		)
		(instances
			(project "sdi-mipi-video-converter"
				(path ""
					(reference "R95")
					(unit 1)
				)
			)
		)
	)
	(symbol
		(lib_id "antmicroMemory:W25Q32JVSNIQ")
		(at 330.2 53.34 0)
		(unit 1)
		(exclude_from_sim no)
		(in_bom yes)
		(on_board yes)
		(dnp no)
		(fields_autoplaced yes)
		(property "Reference" "U18"
			(at 339.725 45.72 0)
			(effects
				(font
					(size 1.27 1.27)
					(thickness 0.15)
				)
			)
		)
		(property "Value" "W25Q32JVSSIQ"
			(at 339.725 45.72 0)
			(effects
				(font
					(size 1.27 1.27)
					(thickness 0.15)
				)
				(hide yes)
			)
		)
		(property "Footprint" "antmicro-footprints:SOIC-8_3.9x4.9x1.75mm_P1.27mm"
			(at 363.22 62.23 0)
			(effects
				(font
					(size 1.27 1.27)
					(thickness 0.15)
				)
				(justify left bottom)
				(hide yes)
			)
		)
		(property "Datasheet" "https://www.mouser.com/datasheet/2/949/w25q32jv_revg_03272018_plus-1489806.pdf"
			(at 363.22 64.77 0)
			(effects
				(font
					(size 1.27 1.27)
					(thickness 0.15)
				)
				(justify left bottom)
				(hide yes)
			)
		)
		(property "Description" "Flash Memory, Serial NOR, 32 Mbit, 4M x 8bit, SPI, SOIC, 8 Pins"
			(at 363.22 77.47 0)
			(effects
				(font
					(size 1.27 1.27)
				)
				(justify left bottom)
				(hide yes)
			)
		)
		(property "MPN" "W25Q32JVSNIQ"
			(at 339.725 48.26 0)
			(effects
				(font
					(size 1.27 1.27)
					(thickness 0.15)
				)
			)
		)
		(property "Manufacturer" "Winbond"
			(at 363.22 69.85 0)
			(effects
				(font
					(size 1.27 1.27)
					(thickness 0.15)
				)
				(justify left bottom)
				(hide yes)
			)
		)
		(property "Author" "Antmicro"
			(at 363.22 72.39 0)
			(effects
				(font
					(size 1.27 1.27)
					(thickness 0.15)
				)
				(justify left bottom)
				(hide yes)
			)
		)
		(property "License" "Apache-2.0"
			(at 363.22 74.93 0)
			(effects
				(font
					(size 1.27 1.27)
					(thickness 0.15)
				)
				(justify left bottom)
				(hide yes)
			)
		)
		(pin "1"
		)
		(pin "2"
		)
		(pin "3"
		)
		(pin "4"
		)
		(pin "5"
		)
		(pin "6"
		)
		(pin "7"
		)
		(pin "8"
		)
		(instances
			(project "sdi-mipi-video-converter"
				(path ""
					(reference "U18")
					(unit 1)
				)
			)
		)
	)
	(symbol
		(lib_id "antmicroGenericPinHeaders:PinHeader_2x5_P1.27mm_SMD_Shrouded")
		(at 351.79 113.03 0)
		(unit 1)
		(exclude_from_sim no)
		(in_bom yes)
		(on_board yes)
		(dnp no)
		(property "Reference" "J7"
			(at 356.87 109.855 0)
			(effects
				(font
					(size 1.27 1.27)
					(thickness 0.15)
				)
			)
		)
		(property "Value" "PinHeader_2x5_P2mm_Drill0.71mm_Shrouded"
			(at 363.22 93.98 0)
			(effects
				(font
					(size 1.27 1.27)
					(thickness 0.15)
				)
			)
		)
		(property "Footprint" "antmicro-footprints:PinHeader_2x5_P1.27mm_SMD_Shrouded"
			(at 377.19 123.19 0)
			(effects
				(font
					(size 1.27 1.27)
					(thickness 0.15)
				)
				(justify left bottom)
				(hide yes)
			)
		)
		(property "Datasheet" "https://eu.mouser.com/datasheet/2/527/shf-1370134.pdf"
			(at 377.19 125.73 0)
			(effects
				(font
					(size 1.27 1.27)
					(thickness 0.15)
				)
				(justify left bottom)
				(hide yes)
			)
		)
		(property "Description" "Headers & Wire Housings Shrouded Terminal Strip, 0.050\" pitch"
			(at 351.79 113.03 0)
			(effects
				(font
					(size 1.27 1.27)
				)
				(hide yes)
			)
		)
		(property "MPN" "SHF-105-01-L-D-SM"
			(at 377.19 128.27 0)
			(effects
				(font
					(size 1.27 1.27)
					(thickness 0.15)
				)
				(justify left bottom)
				(hide yes)
			)
		)
		(property "Manufacturer" "Samtec"
			(at 377.19 130.81 0)
			(effects
				(font
					(size 1.27 1.27)
					(thickness 0.15)
				)
				(justify left bottom)
				(hide yes)
			)
		)
		(property "Author" "Antmicro"
			(at 377.19 133.35 0)
			(effects
				(font
					(size 1.27 1.27)
					(thickness 0.15)
				)
				(justify left bottom)
				(hide yes)
			)
		)
		(property "License" "Apache-2.0"
			(at 377.19 135.89 0)
			(effects
				(font
					(size 1.27 1.27)
					(thickness 0.15)
				)
				(justify left bottom)
				(hide yes)
			)
		)
		(pin "1"
		)
		(pin "10"
		)
		(pin "2"
		)
		(pin "3"
		)
		(pin "4"
		)
		(pin "5"
		)
		(pin "6"
		)
		(pin "7"
		)
		(pin "8"
		)
		(pin "9"
		)
		(instances
			(project "sdi-mipi-video-converter"
				(path ""
					(reference "J7")
					(unit 1)
				)
			)
		)
	)
	(symbol
		(lib_id "antmicroResistors0402:R_0R_0402")
		(at 240.03 132.08 270)
		(mirror x)
		(unit 1)
		(exclude_from_sim no)
		(in_bom yes)
		(on_board yes)
		(dnp no)
		(fields_autoplaced yes)
		(property "Reference" "R66"
			(at 237.49 128.2699 90)
			(effects
				(font
					(size 1.27 1.27)
					(thickness 0.15)
				)
				(justify right)
			)
		)
		(property "Value" "R_0R_0402"
			(at 227.33 111.76 0)
			(effects
				(font
					(size 1.27 1.27)
					(thickness 0.15)
				)
				(justify left bottom)
				(hide yes)
			)
		)
		(property "Footprint" "antmicro-footprints:R_0402_1005Metric"
			(at 224.79 111.76 0)
			(effects
				(font
					(size 1.27 1.27)
					(thickness 0.15)
				)
				(justify left bottom)
				(hide yes)
			)
		)
		(property "Datasheet" "https://industrial.panasonic.com/cdbs/www-data/pdf/RDA0000/AOA0000C301.pdf"
			(at 222.25 111.76 0)
			(effects
				(font
					(size 1.27 1.27)
					(thickness 0.15)
				)
				(justify left bottom)
				(hide yes)
			)
		)
		(property "Description" "SMD Chip Resistor, Jumper, 0 ohm, 100 mW, 0402 [1005 Metric], Thick Film, General Purpose"
			(at 240.03 132.08 0)
			(effects
				(font
					(size 1.27 1.27)
				)
				(hide yes)
			)
		)
		(property "Manufacturer" "Panasonic"
			(at 217.17 111.76 0)
			(effects
				(font
					(size 1.27 1.27)
					(thickness 0.15)
				)
				(justify left bottom)
				(hide yes)
			)
		)
		(property "MPN" "ERJ2GE0R00X"
			(at 219.71 111.76 0)
			(effects
				(font
					(size 1.27 1.27)
					(thickness 0.15)
				)
				(justify left bottom)
				(hide yes)
			)
		)
		(property "Val" "0R"
			(at 237.49 130.8099 90)
			(effects
				(font
					(size 1.27 1.27)
					(thickness 0.15)
				)
				(justify right)
			)
		)
		(property "License" "Apache-2.0"
			(at 214.63 111.76 0)
			(effects
				(font
					(size 1.27 1.27)
					(thickness 0.15)
				)
				(justify left bottom)
				(hide yes)
			)
		)
		(property "Author" "Antmicro"
			(at 212.09 111.76 0)
			(effects
				(font
					(size 1.27 1.27)
					(thickness 0.15)
				)
				(justify left bottom)
				(hide yes)
			)
		)
		(property "Tolerance" "~"
			(at 229.87 111.76 0)
			(effects
				(font
					(size 1.27 1.27)
				)
				(justify left bottom)
				(hide yes)
			)
		)
		(property "Current" "1A"
			(at 209.55 111.76 0)
			(effects
				(font
					(size 1.27 1.27)
					(thickness 0.15)
				)
				(justify left bottom)
				(hide yes)
			)
		)
		(pin "1"
		)
		(pin "2"
		)
		(instances
			(project "sdi-mipi-video-converter"
				(path ""
					(reference "R66")
					(unit 1)
				)
			)
		)
	)
	(symbol
		(lib_id "antmicroTestPoints:TP_0.75mm_SMD")
		(at 300.99 50.8 90)
		(unit 1)
		(exclude_from_sim no)
		(in_bom yes)
		(on_board yes)
		(dnp no)
		(property "Reference" "TP20"
			(at 300.99 41.275 0)
			(effects
				(font
					(size 1.27 1.27)
					(thickness 0.15)
				)
				(justify right)
			)
		)
		(property "Value" "TP_0.75mm_SMD"
			(at 308.61 33.02 0)
			(effects
				(font
					(size 1.27 1.27)
					(thickness 0.15)
				)
				(justify left bottom)
				(hide yes)
			)
		)
		(property "Footprint" "antmicro-footprints:TP_SMD_0.75mm"
			(at 311.15 33.02 0)
			(effects
				(font
					(size 1.27 1.27)
					(thickness 0.15)
				)
				(justify left bottom)
				(hide yes)
			)
		)
		(property "Datasheet" ""
			(at 313.69 33.02 0)
			(effects
				(font
					(size 1.27 1.27)
					(thickness 0.15)
				)
				(justify left bottom)
				(hide yes)
			)
		)
		(property "Description" "SMT test point"
			(at 300.99 50.8 0)
			(effects
				(font
					(size 1.27 1.27)
				)
				(hide yes)
			)
		)
		(property "MPN" ""
			(at 316.23 33.02 0)
			(effects
				(font
					(size 1.27 1.27)
					(thickness 0.15)
				)
				(justify left bottom)
				(hide yes)
			)
		)
		(property "Manufacturer" ""
			(at 318.77 33.02 0)
			(effects
				(font
					(size 1.27 1.27)
					(thickness 0.15)
				)
				(justify left bottom)
				(hide yes)
			)
		)
		(property "Author" "Antmicro"
			(at 321.31 33.02 0)
			(effects
				(font
					(size 1.27 1.27)
					(thickness 0.15)
				)
				(justify left bottom)
				(hide yes)
			)
		)
		(property "License" "Apache-2.0"
			(at 323.85 33.02 0)
			(effects
				(font
					(size 1.27 1.27)
					(thickness 0.15)
				)
				(justify left bottom)
				(hide yes)
			)
		)
		(pin "1"
		)
		(instances
			(project "sdi-mipi-video-converter"
				(path ""
					(reference "TP20")
					(unit 1)
				)
			)
		)
	)
	(symbol
		(lib_id "antmicroResistors0402:R_4k7_0402")
		(at 325.12 46.99 90)
		(unit 1)
		(exclude_from_sim no)
		(in_bom yes)
		(on_board yes)
		(dnp no)
		(property "Reference" "R90"
			(at 326.39 43.18 90)
			(effects
				(font
					(size 1.27 1.27)
					(thickness 0.15)
				)
				(justify right)
			)
		)
		(property "Value" "R_4k7_0402"
			(at 337.82 26.67 0)
			(effects
				(font
					(size 1.27 1.27)
					(thickness 0.15)
				)
				(justify left bottom)
				(hide yes)
			)
		)
		(property "Footprint" "antmicro-footprints:R_0402_1005Metric"
			(at 340.36 26.67 0)
			(effects
				(font
					(size 1.27 1.27)
					(thickness 0.15)
				)
				(justify left bottom)
				(hide yes)
			)
		)
		(property "Datasheet" "https://www.bourns.com/docs/product-datasheets/cr.pdf"
			(at 342.9 26.67 0)
			(effects
				(font
					(size 1.27 1.27)
					(thickness 0.15)
				)
				(justify left bottom)
				(hide yes)
			)
		)
		(property "Description" "SMD Chip Resistor, 4.7 kohm, ± 1%, 62.5 mW, 0402 [1005 Metric], Thick Film, General Purpose"
			(at 325.12 46.99 0)
			(effects
				(font
					(size 1.27 1.27)
				)
				(hide yes)
			)
		)
		(property "Manufacturer" "Bourns"
			(at 347.98 26.67 0)
			(effects
				(font
					(size 1.27 1.27)
					(thickness 0.15)
				)
				(justify left bottom)
				(hide yes)
			)
		)
		(property "MPN" "CR0402-FX-4701GLF"
			(at 345.44 26.67 0)
			(effects
				(font
					(size 1.27 1.27)
					(thickness 0.15)
				)
				(justify left bottom)
				(hide yes)
			)
		)
		(property "Val" "4k7"
			(at 326.39 45.72 90)
			(effects
				(font
					(size 1.27 1.27)
					(thickness 0.15)
				)
				(justify right)
			)
		)
		(property "License" "Apache-2.0"
			(at 350.52 26.67 0)
			(effects
				(font
					(size 1.27 1.27)
					(thickness 0.15)
				)
				(justify left bottom)
				(hide yes)
			)
		)
		(property "Author" "Antmicro"
			(at 353.06 26.67 0)
			(effects
				(font
					(size 1.27 1.27)
					(thickness 0.15)
				)
				(justify left bottom)
				(hide yes)
			)
		)
		(property "Tolerance" "1%"
			(at 335.28 26.67 0)
			(effects
				(font
					(size 1.27 1.27)
				)
				(justify left bottom)
				(hide yes)
			)
		)
		(pin "1"
		)
		(pin "2"
		)
		(instances
			(project "sdi-mipi-video-converter"
				(path ""
					(reference "R90")
					(unit 1)
				)
			)
		)
	)
	(symbol
		(lib_id "antmicroResistors0402:R_0R_0402")
		(at 134.62 257.81 270)
		(mirror x)
		(unit 1)
		(exclude_from_sim no)
		(in_bom yes)
		(on_board yes)
		(dnp no)
		(fields_autoplaced yes)
		(property "Reference" "R39"
			(at 137.16 253.9999 90)
			(effects
				(font
					(size 1.27 1.27)
					(thickness 0.15)
				)
				(justify left)
			)
		)
		(property "Value" "R_0R_0402"
			(at 121.92 237.49 0)
			(effects
				(font
					(size 1.27 1.27)
					(thickness 0.15)
				)
				(justify left bottom)
				(hide yes)
			)
		)
		(property "Footprint" "antmicro-footprints:R_0402_1005Metric"
			(at 119.38 237.49 0)
			(effects
				(font
					(size 1.27 1.27)
					(thickness 0.15)
				)
				(justify left bottom)
				(hide yes)
			)
		)
		(property "Datasheet" "https://industrial.panasonic.com/cdbs/www-data/pdf/RDA0000/AOA0000C301.pdf"
			(at 116.84 237.49 0)
			(effects
				(font
					(size 1.27 1.27)
					(thickness 0.15)
				)
				(justify left bottom)
				(hide yes)
			)
		)
		(property "Description" "SMD Chip Resistor, Jumper, 0 ohm, 100 mW, 0402 [1005 Metric], Thick Film, General Purpose"
			(at 134.62 257.81 0)
			(effects
				(font
					(size 1.27 1.27)
				)
				(hide yes)
			)
		)
		(property "Manufacturer" "Panasonic"
			(at 111.76 237.49 0)
			(effects
				(font
					(size 1.27 1.27)
					(thickness 0.15)
				)
				(justify left bottom)
				(hide yes)
			)
		)
		(property "MPN" "ERJ2GE0R00X"
			(at 114.3 237.49 0)
			(effects
				(font
					(size 1.27 1.27)
					(thickness 0.15)
				)
				(justify left bottom)
				(hide yes)
			)
		)
		(property "Val" "0R"
			(at 137.16 256.5399 90)
			(effects
				(font
					(size 1.27 1.27)
					(thickness 0.15)
				)
				(justify left)
			)
		)
		(property "License" "Apache-2.0"
			(at 109.22 237.49 0)
			(effects
				(font
					(size 1.27 1.27)
					(thickness 0.15)
				)
				(justify left bottom)
				(hide yes)
			)
		)
		(property "Author" "Antmicro"
			(at 106.68 237.49 0)
			(effects
				(font
					(size 1.27 1.27)
					(thickness 0.15)
				)
				(justify left bottom)
				(hide yes)
			)
		)
		(property "Tolerance" "~"
			(at 124.46 237.49 0)
			(effects
				(font
					(size 1.27 1.27)
				)
				(justify left bottom)
				(hide yes)
			)
		)
		(property "Current" "1A"
			(at 104.14 237.49 0)
			(effects
				(font
					(size 1.27 1.27)
					(thickness 0.15)
				)
				(justify left bottom)
				(hide yes)
			)
		)
		(pin "1"
		)
		(pin "2"
		)
		(instances
			(project "sdi-mipi-video-converter"
				(path ""
					(reference "R39")
					(unit 1)
				)
			)
		)
	)
	(symbol
		(lib_id "antmicroTestPoints:TP_0.75mm_SMD")
		(at 289.56 50.8 90)
		(unit 1)
		(exclude_from_sim no)
		(in_bom yes)
		(on_board yes)
		(dnp no)
		(property "Reference" "TP16"
			(at 289.56 41.275 0)
			(effects
				(font
					(size 1.27 1.27)
					(thickness 0.15)
				)
				(justify right)
			)
		)
		(property "Value" "TP_0.75mm_SMD"
			(at 297.18 33.02 0)
			(effects
				(font
					(size 1.27 1.27)
					(thickness 0.15)
				)
				(justify left bottom)
				(hide yes)
			)
		)
		(property "Footprint" "antmicro-footprints:TP_SMD_0.75mm"
			(at 299.72 33.02 0)
			(effects
				(font
					(size 1.27 1.27)
					(thickness 0.15)
				)
				(justify left bottom)
				(hide yes)
			)
		)
		(property "Datasheet" ""
			(at 302.26 33.02 0)
			(effects
				(font
					(size 1.27 1.27)
					(thickness 0.15)
				)
				(justify left bottom)
				(hide yes)
			)
		)
		(property "Description" "SMT test point"
			(at 289.56 50.8 0)
			(effects
				(font
					(size 1.27 1.27)
				)
				(hide yes)
			)
		)
		(property "MPN" ""
			(at 304.8 33.02 0)
			(effects
				(font
					(size 1.27 1.27)
					(thickness 0.15)
				)
				(justify left bottom)
				(hide yes)
			)
		)
		(property "Manufacturer" ""
			(at 307.34 33.02 0)
			(effects
				(font
					(size 1.27 1.27)
					(thickness 0.15)
				)
				(justify left bottom)
				(hide yes)
			)
		)
		(property "Author" "Antmicro"
			(at 309.88 33.02 0)
			(effects
				(font
					(size 1.27 1.27)
					(thickness 0.15)
				)
				(justify left bottom)
				(hide yes)
			)
		)
		(property "License" "Apache-2.0"
			(at 312.42 33.02 0)
			(effects
				(font
					(size 1.27 1.27)
					(thickness 0.15)
				)
				(justify left bottom)
				(hide yes)
			)
		)
		(pin "1"
		)
		(instances
			(project "sdi-mipi-video-converter"
				(path ""
					(reference "TP16")
					(unit 1)
				)
			)
		)
	)
	(symbol
		(lib_id "antmicropower:+3.3V")
		(at 252.73 82.55 0)
		(unit 1)
		(exclude_from_sim no)
		(in_bom yes)
		(on_board yes)
		(dnp no)
		(property "Reference" "#PWR019"
			(at 252.73 86.36 0)
			(effects
				(font
					(size 1.27 1.27)
				)
				(hide yes)
			)
		)
		(property "Value" "+3V3"
			(at 250.19 78.74 0)
			(effects
				(font
					(size 1.27 1.27)
				)
				(justify left)
			)
		)
		(property "Footprint" ""
			(at 252.73 82.55 0)
			(effects
				(font
					(size 1.27 1.27)
				)
				(hide yes)
			)
		)
		(property "Datasheet" ""
			(at 252.73 82.55 0)
			(effects
				(font
					(size 1.27 1.27)
				)
				(hide yes)
			)
		)
		(property "Description" ""
			(at 252.73 82.55 0)
			(effects
				(font
					(size 1.27 1.27)
				)
				(hide yes)
			)
		)
		(pin "1"
		)
		(instances
			(project "sdi-mipi-video-converter"
				(path ""
					(reference "#PWR019")
					(unit 1)
				)
			)
		)
	)
	(symbol
		(lib_id "antmicroLEDIndicationDiscrete:LED_G_0603_LTST-C190GKT")
		(at 316.23 218.44 270)
		(mirror x)
		(unit 1)
		(exclude_from_sim no)
		(in_bom yes)
		(on_board yes)
		(dnp no)
		(fields_autoplaced yes)
		(property "Reference" "D5"
			(at 320.04 214.63 90)
			(effects
				(font
					(size 1.27 1.27)
					(thickness 0.15)
				)
				(justify left)
			)
		)
		(property "Value" "LED_G_0603_LTST-C190GKT"
			(at 320.04 217.17 90)
			(effects
				(font
					(size 1.27 1.27)
					(thickness 0.15)
				)
				(justify left)
			)
		)
		(property "Footprint" "antmicro-footprints:LED_0603_1608Metric_G"
			(at 306.07 195.58 0)
			(effects
				(font
					(size 1.27 1.27)
					(thickness 0.15)
				)
				(justify left bottom)
				(hide yes)
			)
		)
		(property "Datasheet" "https://media.digikey.com/pdf/Data%20Sheets/Lite-On%20PDFs/LTST-C190GKT.pdf"
			(at 303.53 195.58 0)
			(effects
				(font
					(size 1.27 1.27)
					(thickness 0.15)
				)
				(justify left bottom)
				(hide yes)
			)
		)
		(property "Description" "LED, Green, SMD, 0603, 20 mA, 2.1 V, 569 nm"
			(at 316.23 218.44 0)
			(effects
				(font
					(size 1.27 1.27)
				)
				(hide yes)
			)
		)
		(property "MPN" "LTST-C190GKT"
			(at 300.99 195.58 0)
			(effects
				(font
					(size 1.27 1.27)
					(thickness 0.15)
				)
				(justify left bottom)
				(hide yes)
			)
		)
		(property "Manufacturer" "Lite-On"
			(at 298.45 195.58 0)
			(effects
				(font
					(size 1.27 1.27)
					(thickness 0.15)
				)
				(justify left bottom)
				(hide yes)
			)
		)
		(property "Author" "Antmicro"
			(at 295.91 195.58 0)
			(effects
				(font
					(size 1.27 1.27)
					(thickness 0.15)
				)
				(justify left bottom)
				(hide yes)
			)
		)
		(property "License" "Apache-2.0"
			(at 293.37 195.58 0)
			(effects
				(font
					(size 1.27 1.27)
					(thickness 0.15)
				)
				(justify left bottom)
				(hide yes)
			)
		)
		(property "Color" "Green"
			(at 320.04 218.4399 90)
			(effects
				(font
					(size 1.27 1.27)
				)
				(justify left)
				(hide yes)
			)
		)
		(pin "1"
		)
		(pin "2"
		)
		(instances
			(project "sdi-mipi-video-converter"
				(path ""
					(reference "D5")
					(unit 1)
				)
			)
		)
	)
	(symbol
		(lib_id "antmicropower:GND")
		(at 378.46 134.62 0)
		(unit 1)
		(exclude_from_sim no)
		(in_bom yes)
		(on_board yes)
		(dnp no)
		(fields_autoplaced yes)
		(property "Reference" "#PWR0186"
			(at 387.35 137.16 0)
			(effects
				(font
					(size 1.27 1.27)
					(thickness 0.15)
				)
				(justify left bottom)
				(hide yes)
			)
		)
		(property "Value" "GND"
			(at 378.46 139.7 0)
			(effects
				(font
					(size 1.27 1.27)
					(thickness 0.15)
				)
			)
		)
		(property "Footprint" ""
			(at 387.35 142.24 0)
			(effects
				(font
					(size 1.27 1.27)
					(thickness 0.15)
				)
				(justify left bottom)
				(hide yes)
			)
		)
		(property "Datasheet" ""
			(at 387.35 147.32 0)
			(effects
				(font
					(size 1.27 1.27)
					(thickness 0.15)
				)
				(justify left bottom)
				(hide yes)
			)
		)
		(property "Description" ""
			(at 378.46 134.62 0)
			(effects
				(font
					(size 1.27 1.27)
				)
				(hide yes)
			)
		)
		(property "Author" "Antmicro"
			(at 387.35 142.24 0)
			(effects
				(font
					(size 1.27 1.27)
					(thickness 0.15)
				)
				(justify left bottom)
				(hide yes)
			)
		)
		(property "License" "Apache-2.0"
			(at 387.35 144.78 0)
			(effects
				(font
					(size 1.27 1.27)
					(thickness 0.15)
				)
				(justify left bottom)
				(hide yes)
			)
		)
		(pin "1"
		)
		(instances
			(project "sdi-mipi-video-converter"
				(path ""
					(reference "#PWR0186")
					(unit 1)
				)
			)
		)
	)
	(symbol
		(lib_id "antmicropower:+3.3V")
		(at 243.84 123.19 0)
		(mirror y)
		(unit 1)
		(exclude_from_sim no)
		(in_bom yes)
		(on_board yes)
		(dnp no)
		(fields_autoplaced yes)
		(property "Reference" "#PWR0173"
			(at 243.84 127 0)
			(effects
				(font
					(size 1.27 1.27)
				)
				(hide yes)
			)
		)
		(property "Value" "+3V3"
			(at 243.84 118.11 0)
			(effects
				(font
					(size 1.27 1.27)
				)
			)
		)
		(property "Footprint" ""
			(at 243.84 123.19 0)
			(effects
				(font
					(size 1.27 1.27)
				)
				(hide yes)
			)
		)
		(property "Datasheet" ""
			(at 243.84 123.19 0)
			(effects
				(font
					(size 1.27 1.27)
				)
				(hide yes)
			)
		)
		(property "Description" ""
			(at 243.84 123.19 0)
			(effects
				(font
					(size 1.27 1.27)
				)
				(hide yes)
			)
		)
		(pin "1"
		)
		(instances
			(project "sdi-mipi-video-converter"
				(path ""
					(reference "#PWR0173")
					(unit 1)
				)
			)
		)
	)
	(symbol
		(lib_id "antmicropower:GND")
		(at 234.95 236.22 0)
		(unit 1)
		(exclude_from_sim no)
		(in_bom yes)
		(on_board yes)
		(dnp no)
		(fields_autoplaced yes)
		(property "Reference" "#PWR0169"
			(at 243.84 238.76 0)
			(effects
				(font
					(size 1.27 1.27)
					(thickness 0.15)
				)
				(justify left bottom)
				(hide yes)
			)
		)
		(property "Value" "GND"
			(at 234.95 241.3 0)
			(effects
				(font
					(size 1.27 1.27)
					(thickness 0.15)
				)
			)
		)
		(property "Footprint" ""
			(at 243.84 243.84 0)
			(effects
				(font
					(size 1.27 1.27)
					(thickness 0.15)
				)
				(justify left bottom)
				(hide yes)
			)
		)
		(property "Datasheet" ""
			(at 243.84 248.92 0)
			(effects
				(font
					(size 1.27 1.27)
					(thickness 0.15)
				)
				(justify left bottom)
				(hide yes)
			)
		)
		(property "Description" ""
			(at 234.95 236.22 0)
			(effects
				(font
					(size 1.27 1.27)
				)
				(hide yes)
			)
		)
		(property "Author" "Antmicro"
			(at 243.84 243.84 0)
			(effects
				(font
					(size 1.27 1.27)
					(thickness 0.15)
				)
				(justify left bottom)
				(hide yes)
			)
		)
		(property "License" "Apache-2.0"
			(at 243.84 246.38 0)
			(effects
				(font
					(size 1.27 1.27)
					(thickness 0.15)
				)
				(justify left bottom)
				(hide yes)
			)
		)
		(pin "1"
		)
		(instances
			(project "sdi-mipi-video-converter"
				(path ""
					(reference "#PWR0169")
					(unit 1)
				)
			)
		)
	)
	(symbol
		(lib_id "antmicropower:GND")
		(at 251.46 165.1 0)
		(unit 1)
		(exclude_from_sim no)
		(in_bom yes)
		(on_board yes)
		(dnp no)
		(fields_autoplaced yes)
		(property "Reference" "#PWR0171"
			(at 260.35 167.64 0)
			(effects
				(font
					(size 1.27 1.27)
					(thickness 0.15)
				)
				(justify left bottom)
				(hide yes)
			)
		)
		(property "Value" "GND"
			(at 251.46 170.18 0)
			(effects
				(font
					(size 1.27 1.27)
					(thickness 0.15)
				)
			)
		)
		(property "Footprint" ""
			(at 260.35 172.72 0)
			(effects
				(font
					(size 1.27 1.27)
					(thickness 0.15)
				)
				(justify left bottom)
				(hide yes)
			)
		)
		(property "Datasheet" ""
			(at 260.35 177.8 0)
			(effects
				(font
					(size 1.27 1.27)
					(thickness 0.15)
				)
				(justify left bottom)
				(hide yes)
			)
		)
		(property "Description" ""
			(at 251.46 165.1 0)
			(effects
				(font
					(size 1.27 1.27)
				)
				(hide yes)
			)
		)
		(property "Author" "Antmicro"
			(at 260.35 172.72 0)
			(effects
				(font
					(size 1.27 1.27)
					(thickness 0.15)
				)
				(justify left bottom)
				(hide yes)
			)
		)
		(property "License" "Apache-2.0"
			(at 260.35 175.26 0)
			(effects
				(font
					(size 1.27 1.27)
					(thickness 0.15)
				)
				(justify left bottom)
				(hide yes)
			)
		)
		(pin "1"
		)
		(instances
			(project "sdi-mipi-video-converter"
				(path ""
					(reference "#PWR0171")
					(unit 1)
				)
			)
		)
	)
	(symbol
		(lib_id "antmicropower:GND")
		(at 251.46 240.03 0)
		(unit 1)
		(exclude_from_sim no)
		(in_bom yes)
		(on_board yes)
		(dnp no)
		(fields_autoplaced yes)
		(property "Reference" "#PWR0170"
			(at 260.35 242.57 0)
			(effects
				(font
					(size 1.27 1.27)
					(thickness 0.15)
				)
				(justify left bottom)
				(hide yes)
			)
		)
		(property "Value" "GND"
			(at 251.46 245.11 0)
			(effects
				(font
					(size 1.27 1.27)
					(thickness 0.15)
				)
			)
		)
		(property "Footprint" ""
			(at 260.35 247.65 0)
			(effects
				(font
					(size 1.27 1.27)
					(thickness 0.15)
				)
				(justify left bottom)
				(hide yes)
			)
		)
		(property "Datasheet" ""
			(at 260.35 252.73 0)
			(effects
				(font
					(size 1.27 1.27)
					(thickness 0.15)
				)
				(justify left bottom)
				(hide yes)
			)
		)
		(property "Description" ""
			(at 251.46 240.03 0)
			(effects
				(font
					(size 1.27 1.27)
				)
				(hide yes)
			)
		)
		(property "Author" "Antmicro"
			(at 260.35 247.65 0)
			(effects
				(font
					(size 1.27 1.27)
					(thickness 0.15)
				)
				(justify left bottom)
				(hide yes)
			)
		)
		(property "License" "Apache-2.0"
			(at 260.35 250.19 0)
			(effects
				(font
					(size 1.27 1.27)
					(thickness 0.15)
				)
				(justify left bottom)
				(hide yes)
			)
		)
		(pin "1"
		)
		(instances
			(project "sdi-mipi-video-converter"
				(path ""
					(reference "#PWR0170")
					(unit 1)
				)
			)
		)
	)
	(symbol
		(lib_id "antmicroResistors0603:R_0R_0603")
		(at 233.68 147.32 180)
		(unit 1)
		(exclude_from_sim no)
		(in_bom yes)
		(on_board yes)
		(dnp no)
		(property "Reference" "R65"
			(at 235.585 146.05 0)
			(effects
				(font
					(size 1.27 1.27)
					(thickness 0.15)
				)
			)
		)
		(property "Value" "R_0R_0603"
			(at 213.36 134.62 0)
			(effects
				(font
					(size 1.27 1.27)
					(thickness 0.15)
				)
				(justify left bottom)
				(hide yes)
			)
		)
		(property "Footprint" "antmicro-footprints:R_0603_1608Metric"
			(at 213.36 132.08 0)
			(effects
				(font
					(size 1.27 1.27)
					(thickness 0.15)
				)
				(justify left bottom)
				(hide yes)
			)
		)
		(property "Datasheet" "https://www.bourns.com/docs/product-datasheets/cr.pdf?sfvrsn=574d41f6_14"
			(at 213.36 129.54 0)
			(effects
				(font
					(size 1.27 1.27)
					(thickness 0.15)
				)
				(justify left bottom)
				(hide yes)
			)
		)
		(property "Description" "Zero Ohm Resistor, Jumper, 0603 [1608 Metric], Thick Film, 100 mW, 1 A, Surface Mount Device, CR"
			(at 233.68 147.32 0)
			(effects
				(font
					(size 1.27 1.27)
				)
				(hide yes)
			)
		)
		(property "Manufacturer" "Bourns"
			(at 213.36 124.46 0)
			(effects
				(font
					(size 1.27 1.27)
					(thickness 0.15)
				)
				(justify left bottom)
				(hide yes)
			)
		)
		(property "MPN" "CR0603-J/-000ELF"
			(at 213.36 127 0)
			(effects
				(font
					(size 1.27 1.27)
					(thickness 0.15)
				)
				(justify left bottom)
				(hide yes)
			)
		)
		(property "Val" "0R"
			(at 227.33 146.05 0)
			(effects
				(font
					(size 1.27 1.27)
					(thickness 0.15)
				)
			)
		)
		(property "License" "Apache-2.0"
			(at 213.36 121.92 0)
			(effects
				(font
					(size 1.27 1.27)
					(thickness 0.15)
				)
				(justify left bottom)
				(hide yes)
			)
		)
		(property "Author" "Antmicro"
			(at 213.36 119.38 0)
			(effects
				(font
					(size 1.27 1.27)
					(thickness 0.15)
				)
				(justify left bottom)
				(hide yes)
			)
		)
		(property "Tolerance" "~"
			(at 213.36 137.16 0)
			(effects
				(font
					(size 1.27 1.27)
				)
				(justify left bottom)
				(hide yes)
			)
		)
		(property "Current" "1A"
			(at 213.36 116.84 0)
			(effects
				(font
					(size 1.27 1.27)
					(thickness 0.15)
				)
				(justify left bottom)
				(hide yes)
			)
		)
		(pin "1"
		)
		(pin "2"
		)
		(instances
			(project "sdi-mipi-video-converter"
				(path ""
					(reference "R65")
					(unit 1)
				)
			)
		)
	)
	(symbol
		(lib_id "antmicroTestPoints:TP_0.75mm_SMD")
		(at 304.8 50.8 90)
		(unit 1)
		(exclude_from_sim no)
		(in_bom yes)
		(on_board yes)
		(dnp no)
		(property "Reference" "TP21"
			(at 304.8 43.815 0)
			(effects
				(font
					(size 1.27 1.27)
					(thickness 0.15)
				)
			)
		)
		(property "Value" "TP_0.75mm_SMD"
			(at 312.42 33.02 0)
			(effects
				(font
					(size 1.27 1.27)
					(thickness 0.15)
				)
				(justify left bottom)
				(hide yes)
			)
		)
		(property "Footprint" "antmicro-footprints:TP_SMD_0.75mm"
			(at 314.96 33.02 0)
			(effects
				(font
					(size 1.27 1.27)
					(thickness 0.15)
				)
				(justify left bottom)
				(hide yes)
			)
		)
		(property "Datasheet" ""
			(at 317.5 33.02 0)
			(effects
				(font
					(size 1.27 1.27)
					(thickness 0.15)
				)
				(justify left bottom)
				(hide yes)
			)
		)
		(property "Description" "SMT test point"
			(at 304.8 50.8 0)
			(effects
				(font
					(size 1.27 1.27)
				)
				(hide yes)
			)
		)
		(property "MPN" ""
			(at 320.04 33.02 0)
			(effects
				(font
					(size 1.27 1.27)
					(thickness 0.15)
				)
				(justify left bottom)
				(hide yes)
			)
		)
		(property "Manufacturer" ""
			(at 322.58 33.02 0)
			(effects
				(font
					(size 1.27 1.27)
					(thickness 0.15)
				)
				(justify left bottom)
				(hide yes)
			)
		)
		(property "Author" "Antmicro"
			(at 325.12 33.02 0)
			(effects
				(font
					(size 1.27 1.27)
					(thickness 0.15)
				)
				(justify left bottom)
				(hide yes)
			)
		)
		(property "License" "Apache-2.0"
			(at 327.66 33.02 0)
			(effects
				(font
					(size 1.27 1.27)
					(thickness 0.15)
				)
				(justify left bottom)
				(hide yes)
			)
		)
		(pin "1"
		)
		(instances
			(project "sdi-mipi-video-converter"
				(path ""
					(reference "TP21")
					(unit 1)
				)
			)
		)
	)
	(symbol
		(lib_id "antmicropower:+3.3V")
		(at 349.25 110.49 0)
		(mirror y)
		(unit 1)
		(exclude_from_sim no)
		(in_bom yes)
		(on_board yes)
		(dnp no)
		(fields_autoplaced yes)
		(property "Reference" "#PWR0181"
			(at 349.25 114.3 0)
			(effects
				(font
					(size 1.27 1.27)
				)
				(hide yes)
			)
		)
		(property "Value" "+3V3"
			(at 349.25 105.41 0)
			(effects
				(font
					(size 1.27 1.27)
				)
			)
		)
		(property "Footprint" ""
			(at 349.25 110.49 0)
			(effects
				(font
					(size 1.27 1.27)
				)
				(hide yes)
			)
		)
		(property "Datasheet" ""
			(at 349.25 110.49 0)
			(effects
				(font
					(size 1.27 1.27)
				)
				(hide yes)
			)
		)
		(property "Description" ""
			(at 349.25 110.49 0)
			(effects
				(font
					(size 1.27 1.27)
				)
				(hide yes)
			)
		)
		(pin "1"
		)
		(instances
			(project "sdi-mipi-video-converter"
				(path ""
					(reference "#PWR0181")
					(unit 1)
				)
			)
		)
	)
	(symbol
		(lib_id "antmicropower:GND")
		(at 252.73 90.17 0)
		(unit 1)
		(exclude_from_sim no)
		(in_bom yes)
		(on_board yes)
		(dnp no)
		(fields_autoplaced yes)
		(property "Reference" "#PWR021"
			(at 261.62 92.71 0)
			(effects
				(font
					(size 1.27 1.27)
					(thickness 0.15)
				)
				(justify left bottom)
				(hide yes)
			)
		)
		(property "Value" "GND"
			(at 252.73 95.25 0)
			(effects
				(font
					(size 1.27 1.27)
					(thickness 0.15)
				)
			)
		)
		(property "Footprint" ""
			(at 261.62 97.79 0)
			(effects
				(font
					(size 1.27 1.27)
					(thickness 0.15)
				)
				(justify left bottom)
				(hide yes)
			)
		)
		(property "Datasheet" ""
			(at 261.62 102.87 0)
			(effects
				(font
					(size 1.27 1.27)
					(thickness 0.15)
				)
				(justify left bottom)
				(hide yes)
			)
		)
		(property "Description" ""
			(at 252.73 90.17 0)
			(effects
				(font
					(size 1.27 1.27)
				)
				(hide yes)
			)
		)
		(property "Author" "Antmicro"
			(at 261.62 97.79 0)
			(effects
				(font
					(size 1.27 1.27)
					(thickness 0.15)
				)
				(justify left bottom)
				(hide yes)
			)
		)
		(property "License" "Apache-2.0"
			(at 261.62 100.33 0)
			(effects
				(font
					(size 1.27 1.27)
					(thickness 0.15)
				)
				(justify left bottom)
				(hide yes)
			)
		)
		(pin "1"
		)
		(instances
			(project "sdi-mipi-video-converter"
				(path ""
					(reference "#PWR021")
					(unit 1)
				)
			)
		)
	)
	(symbol
		(lib_id "antmicroResistors0402:R_2k2_0402")
		(at 316.23 210.82 90)
		(unit 1)
		(exclude_from_sim no)
		(in_bom yes)
		(on_board yes)
		(dnp no)
		(fields_autoplaced yes)
		(property "Reference" "R89"
			(at 318.77 207.0099 90)
			(effects
				(font
					(size 1.27 1.27)
					(thickness 0.15)
				)
				(justify right)
			)
		)
		(property "Value" "R_2k2_0402"
			(at 328.93 190.5 0)
			(effects
				(font
					(size 1.27 1.27)
					(thickness 0.15)
				)
				(justify left bottom)
				(hide yes)
			)
		)
		(property "Footprint" "antmicro-footprints:R_0402_1005Metric"
			(at 331.47 190.5 0)
			(effects
				(font
					(size 1.27 1.27)
					(thickness 0.15)
				)
				(justify left bottom)
				(hide yes)
			)
		)
		(property "Datasheet" "https://www.bourns.com/docs/product-datasheets/cr.pdf"
			(at 334.01 190.5 0)
			(effects
				(font
					(size 1.27 1.27)
					(thickness 0.15)
				)
				(justify left bottom)
				(hide yes)
			)
		)
		(property "Description" "SMD Chip Resistor, 2.2 kohm, ± 1%, 62.5 mW, 0402 [1005 Metric], Thick Film, General Purpose"
			(at 316.23 210.82 0)
			(effects
				(font
					(size 1.27 1.27)
				)
				(hide yes)
			)
		)
		(property "Manufacturer" "Bourns"
			(at 339.09 190.5 0)
			(effects
				(font
					(size 1.27 1.27)
					(thickness 0.15)
				)
				(justify left bottom)
				(hide yes)
			)
		)
		(property "MPN" "CR0402-FX-2201GLF"
			(at 336.55 190.5 0)
			(effects
				(font
					(size 1.27 1.27)
					(thickness 0.15)
				)
				(justify left bottom)
				(hide yes)
			)
		)
		(property "Val" "2k2"
			(at 318.77 209.5499 90)
			(effects
				(font
					(size 1.27 1.27)
					(thickness 0.15)
				)
				(justify right)
			)
		)
		(property "License" "Apache-2.0"
			(at 341.63 190.5 0)
			(effects
				(font
					(size 1.27 1.27)
					(thickness 0.15)
				)
				(justify left bottom)
				(hide yes)
			)
		)
		(property "Author" "Antmicro"
			(at 344.17 190.5 0)
			(effects
				(font
					(size 1.27 1.27)
					(thickness 0.15)
				)
				(justify left bottom)
				(hide yes)
			)
		)
		(property "Tolerance" "1%"
			(at 326.39 190.5 0)
			(effects
				(font
					(size 1.27 1.27)
				)
				(justify left bottom)
				(hide yes)
			)
		)
		(pin "1"
		)
		(pin "2"
		)
		(instances
			(project "sdi-mipi-video-converter"
				(path ""
					(reference "R89")
					(unit 1)
				)
			)
		)
	)
	(symbol
		(lib_id "antmicroResistors0402:R_10k_0402")
		(at 378.46 133.35 90)
		(unit 1)
		(exclude_from_sim no)
		(in_bom yes)
		(on_board yes)
		(dnp no)
		(fields_autoplaced yes)
		(property "Reference" "R97"
			(at 381 129.5399 90)
			(effects
				(font
					(size 1.27 1.27)
					(thickness 0.15)
				)
				(justify right)
			)
		)
		(property "Value" "R_10k_0402"
			(at 391.16 113.03 0)
			(effects
				(font
					(size 1.27 1.27)
					(thickness 0.15)
				)
				(justify left bottom)
				(hide yes)
			)
		)
		(property "Footprint" "antmicro-footprints:R_0402_1005Metric"
			(at 393.7 113.03 0)
			(effects
				(font
					(size 1.27 1.27)
					(thickness 0.15)
				)
				(justify left bottom)
				(hide yes)
			)
		)
		(property "Datasheet" "https://www.bourns.com/docs/product-datasheets/cr.pdf"
			(at 396.24 113.03 0)
			(effects
				(font
					(size 1.27 1.27)
					(thickness 0.15)
				)
				(justify left bottom)
				(hide yes)
			)
		)
		(property "Description" "SMD Chip Resistor, 10 kohm, ± 1%, 62.5 mW, 0402 [1005 Metric], Thick Film, General Purpose"
			(at 378.46 133.35 0)
			(effects
				(font
					(size 1.27 1.27)
				)
				(hide yes)
			)
		)
		(property "Manufacturer" "Bourns"
			(at 401.32 113.03 0)
			(effects
				(font
					(size 1.27 1.27)
					(thickness 0.15)
				)
				(justify left bottom)
				(hide yes)
			)
		)
		(property "MPN" "CR0402-FX-1002GLF"
			(at 398.78 113.03 0)
			(effects
				(font
					(size 1.27 1.27)
					(thickness 0.15)
				)
				(justify left bottom)
				(hide yes)
			)
		)
		(property "Val" "10k"
			(at 381 132.0799 90)
			(effects
				(font
					(size 1.27 1.27)
					(thickness 0.15)
				)
				(justify right)
			)
		)
		(property "License" "Apache-2.0"
			(at 403.86 113.03 0)
			(effects
				(font
					(size 1.27 1.27)
					(thickness 0.15)
				)
				(justify left bottom)
				(hide yes)
			)
		)
		(property "Author" "Antmicro"
			(at 406.4 113.03 0)
			(effects
				(font
					(size 1.27 1.27)
					(thickness 0.15)
				)
				(justify left bottom)
				(hide yes)
			)
		)
		(property "Tolerance" "1%"
			(at 388.62 113.03 0)
			(effects
				(font
					(size 1.27 1.27)
				)
				(justify left bottom)
				(hide yes)
			)
		)
		(pin "1"
		)
		(pin "2"
		)
		(instances
			(project "sdi-mipi-video-converter"
				(path ""
					(reference "R97")
					(unit 1)
				)
			)
		)
	)
	(symbol
		(lib_id "antmicropower:GND")
		(at 91.44 156.21 0)
		(unit 1)
		(exclude_from_sim no)
		(in_bom yes)
		(on_board yes)
		(dnp no)
		(fields_autoplaced yes)
		(property "Reference" "#PWR0216"
			(at 100.33 158.75 0)
			(effects
				(font
					(size 1.27 1.27)
					(thickness 0.15)
				)
				(justify left bottom)
				(hide yes)
			)
		)
		(property "Value" "GND"
			(at 91.44 161.29 0)
			(effects
				(font
					(size 1.27 1.27)
					(thickness 0.15)
				)
			)
		)
		(property "Footprint" ""
			(at 100.33 163.83 0)
			(effects
				(font
					(size 1.27 1.27)
					(thickness 0.15)
				)
				(justify left bottom)
				(hide yes)
			)
		)
		(property "Datasheet" ""
			(at 100.33 168.91 0)
			(effects
				(font
					(size 1.27 1.27)
					(thickness 0.15)
				)
				(justify left bottom)
				(hide yes)
			)
		)
		(property "Description" ""
			(at 91.44 156.21 0)
			(effects
				(font
					(size 1.27 1.27)
				)
				(hide yes)
			)
		)
		(property "Author" "Antmicro"
			(at 100.33 163.83 0)
			(effects
				(font
					(size 1.27 1.27)
					(thickness 0.15)
				)
				(justify left bottom)
				(hide yes)
			)
		)
		(property "License" "Apache-2.0"
			(at 100.33 166.37 0)
			(effects
				(font
					(size 1.27 1.27)
					(thickness 0.15)
				)
				(justify left bottom)
				(hide yes)
			)
		)
		(pin "1"
		)
		(instances
			(project "sdi-mipi-video-converter"
				(path ""
					(reference "#PWR0216")
					(unit 1)
				)
			)
		)
	)
	(symbol
		(lib_id "antmicropower:GND")
		(at 140.97 153.67 0)
		(unit 1)
		(exclude_from_sim no)
		(in_bom yes)
		(on_board yes)
		(dnp no)
		(fields_autoplaced yes)
		(property "Reference" "#PWR0217"
			(at 149.86 156.21 0)
			(effects
				(font
					(size 1.27 1.27)
					(thickness 0.15)
				)
				(justify left bottom)
				(hide yes)
			)
		)
		(property "Value" "GND"
			(at 140.97 158.75 0)
			(effects
				(font
					(size 1.27 1.27)
					(thickness 0.15)
				)
			)
		)
		(property "Footprint" ""
			(at 149.86 161.29 0)
			(effects
				(font
					(size 1.27 1.27)
					(thickness 0.15)
				)
				(justify left bottom)
				(hide yes)
			)
		)
		(property "Datasheet" ""
			(at 149.86 166.37 0)
			(effects
				(font
					(size 1.27 1.27)
					(thickness 0.15)
				)
				(justify left bottom)
				(hide yes)
			)
		)
		(property "Description" ""
			(at 140.97 153.67 0)
			(effects
				(font
					(size 1.27 1.27)
				)
				(hide yes)
			)
		)
		(property "Author" "Antmicro"
			(at 149.86 161.29 0)
			(effects
				(font
					(size 1.27 1.27)
					(thickness 0.15)
				)
				(justify left bottom)
				(hide yes)
			)
		)
		(property "License" "Apache-2.0"
			(at 149.86 163.83 0)
			(effects
				(font
					(size 1.27 1.27)
					(thickness 0.15)
				)
				(justify left bottom)
				(hide yes)
			)
		)
		(pin "1"
		)
		(instances
			(project "sdi-mipi-video-converter"
				(path ""
					(reference "#PWR0217")
					(unit 1)
				)
			)
		)
	)
	(symbol
		(lib_id "antmicroResistors0402:R_0R_0402")
		(at 241.3 158.75 90)
		(mirror x)
		(unit 1)
		(exclude_from_sim no)
		(in_bom yes)
		(on_board yes)
		(dnp no)
		(property "Reference" "R78"
			(at 242.57 160.02 90)
			(effects
				(font
					(size 1.27 1.27)
					(thickness 0.15)
				)
				(justify right)
			)
		)
		(property "Value" "R_0R_0402"
			(at 254 179.07 0)
			(effects
				(font
					(size 1.27 1.27)
					(thickness 0.15)
				)
				(justify left bottom)
				(hide yes)
			)
		)
		(property "Footprint" "antmicro-footprints:R_0402_1005Metric"
			(at 256.54 179.07 0)
			(effects
				(font
					(size 1.27 1.27)
					(thickness 0.15)
				)
				(justify left bottom)
				(hide yes)
			)
		)
		(property "Datasheet" "https://industrial.panasonic.com/cdbs/www-data/pdf/RDA0000/AOA0000C301.pdf"
			(at 259.08 179.07 0)
			(effects
				(font
					(size 1.27 1.27)
					(thickness 0.15)
				)
				(justify left bottom)
				(hide yes)
			)
		)
		(property "Description" "SMD Chip Resistor, Jumper, 0 ohm, 100 mW, 0402 [1005 Metric], Thick Film, General Purpose"
			(at 241.3 158.75 0)
			(effects
				(font
					(size 1.27 1.27)
				)
				(hide yes)
			)
		)
		(property "Manufacturer" "Panasonic"
			(at 264.16 179.07 0)
			(effects
				(font
					(size 1.27 1.27)
					(thickness 0.15)
				)
				(justify left bottom)
				(hide yes)
			)
		)
		(property "MPN" "ERJ2GE0R00X"
			(at 261.62 179.07 0)
			(effects
				(font
					(size 1.27 1.27)
					(thickness 0.15)
				)
				(justify left bottom)
				(hide yes)
			)
		)
		(property "Val" "0R"
			(at 242.57 162.56 90)
			(effects
				(font
					(size 1.27 1.27)
					(thickness 0.15)
				)
				(justify right)
			)
		)
		(property "License" "Apache-2.0"
			(at 266.7 179.07 0)
			(effects
				(font
					(size 1.27 1.27)
					(thickness 0.15)
				)
				(justify left bottom)
				(hide yes)
			)
		)
		(property "Author" "Antmicro"
			(at 269.24 179.07 0)
			(effects
				(font
					(size 1.27 1.27)
					(thickness 0.15)
				)
				(justify left bottom)
				(hide yes)
			)
		)
		(property "Tolerance" "~"
			(at 251.46 179.07 0)
			(effects
				(font
					(size 1.27 1.27)
				)
				(justify left bottom)
				(hide yes)
			)
		)
		(property "Current" "1A"
			(at 271.78 179.07 0)
			(effects
				(font
					(size 1.27 1.27)
					(thickness 0.15)
				)
				(justify left bottom)
				(hide yes)
			)
		)
		(pin "1"
		)
		(pin "2"
		)
		(instances
			(project "sdi-mipi-video-converter"
				(path ""
					(reference "R78")
					(unit 1)
				)
			)
		)
	)
	(symbol
		(lib_id "antmicropower:GND")
		(at 257.81 92.71 0)
		(unit 1)
		(exclude_from_sim no)
		(in_bom yes)
		(on_board yes)
		(dnp no)
		(fields_autoplaced yes)
		(property "Reference" "#PWR022"
			(at 266.7 95.25 0)
			(effects
				(font
					(size 1.27 1.27)
					(thickness 0.15)
				)
				(justify left bottom)
				(hide yes)
			)
		)
		(property "Value" "GND"
			(at 257.81 97.79 0)
			(effects
				(font
					(size 1.27 1.27)
					(thickness 0.15)
				)
			)
		)
		(property "Footprint" ""
			(at 266.7 100.33 0)
			(effects
				(font
					(size 1.27 1.27)
					(thickness 0.15)
				)
				(justify left bottom)
				(hide yes)
			)
		)
		(property "Datasheet" ""
			(at 266.7 105.41 0)
			(effects
				(font
					(size 1.27 1.27)
					(thickness 0.15)
				)
				(justify left bottom)
				(hide yes)
			)
		)
		(property "Description" ""
			(at 257.81 92.71 0)
			(effects
				(font
					(size 1.27 1.27)
				)
				(hide yes)
			)
		)
		(property "Author" "Antmicro"
			(at 266.7 100.33 0)
			(effects
				(font
					(size 1.27 1.27)
					(thickness 0.15)
				)
				(justify left bottom)
				(hide yes)
			)
		)
		(property "License" "Apache-2.0"
			(at 266.7 102.87 0)
			(effects
				(font
					(size 1.27 1.27)
					(thickness 0.15)
				)
				(justify left bottom)
				(hide yes)
			)
		)
		(pin "1"
		)
		(instances
			(project "sdi-mipi-video-converter"
				(path ""
					(reference "#PWR022")
					(unit 1)
				)
			)
		)
	)
	(symbol
		(lib_id "antmicroResistors0402:R_0R_0402")
		(at 298.45 154.94 180)
		(unit 1)
		(exclude_from_sim no)
		(in_bom yes)
		(on_board yes)
		(dnp no)
		(property "Reference" "R141"
			(at 290.83 156.21 0)
			(effects
				(font
					(size 1.27 1.27)
					(thickness 0.15)
				)
			)
		)
		(property "Value" "R_0R_0402"
			(at 278.13 142.24 0)
			(effects
				(font
					(size 1.27 1.27)
					(thickness 0.15)
				)
				(justify left bottom)
				(hide yes)
			)
		)
		(property "Footprint" "antmicro-footprints:R_0402_1005Metric"
			(at 278.13 139.7 0)
			(effects
				(font
					(size 1.27 1.27)
					(thickness 0.15)
				)
				(justify left bottom)
				(hide yes)
			)
		)
		(property "Datasheet" "https://industrial.panasonic.com/cdbs/www-data/pdf/RDA0000/AOA0000C301.pdf"
			(at 278.13 137.16 0)
			(effects
				(font
					(size 1.27 1.27)
					(thickness 0.15)
				)
				(justify left bottom)
				(hide yes)
			)
		)
		(property "Description" "SMD Chip Resistor, Jumper, 0 ohm, 100 mW, 0402 [1005 Metric], Thick Film, General Purpose"
			(at 298.45 154.94 0)
			(effects
				(font
					(size 1.27 1.27)
				)
				(hide yes)
			)
		)
		(property "Manufacturer" "Panasonic"
			(at 278.13 132.08 0)
			(effects
				(font
					(size 1.27 1.27)
					(thickness 0.15)
				)
				(justify left bottom)
				(hide yes)
			)
		)
		(property "MPN" "ERJ2GE0R00X"
			(at 278.13 134.62 0)
			(effects
				(font
					(size 1.27 1.27)
					(thickness 0.15)
				)
				(justify left bottom)
				(hide yes)
			)
		)
		(property "Val" "0R"
			(at 299.72 156.21 0)
			(effects
				(font
					(size 1.27 1.27)
					(thickness 0.15)
				)
			)
		)
		(property "License" "Apache-2.0"
			(at 278.13 129.54 0)
			(effects
				(font
					(size 1.27 1.27)
					(thickness 0.15)
				)
				(justify left bottom)
				(hide yes)
			)
		)
		(property "Author" "Antmicro"
			(at 278.13 127 0)
			(effects
				(font
					(size 1.27 1.27)
					(thickness 0.15)
				)
				(justify left bottom)
				(hide yes)
			)
		)
		(property "Tolerance" "~"
			(at 278.13 144.78 0)
			(effects
				(font
					(size 1.27 1.27)
				)
				(justify left bottom)
				(hide yes)
			)
		)
		(property "Current" "1A"
			(at 278.13 124.46 0)
			(effects
				(font
					(size 1.27 1.27)
					(thickness 0.15)
				)
				(justify left bottom)
				(hide yes)
			)
		)
		(pin "1"
		)
		(pin "2"
		)
		(instances
			(project "sdi-mipi-video-converter"
				(path ""
					(reference "R141")
					(unit 1)
				)
			)
		)
	)
	(symbol
		(lib_id "antmicroCapacitors0402:C_100n_0402")
		(at 234.95 234.95 90)
		(unit 1)
		(exclude_from_sim no)
		(in_bom yes)
		(on_board yes)
		(dnp no)
		(fields_autoplaced yes)
		(property "Reference" "C80"
			(at 232.41 231.1335 90)
			(effects
				(font
					(size 1.27 1.27)
					(thickness 0.15)
				)
				(justify left)
			)
		)
		(property "Value" "C_100n_0402"
			(at 245.11 214.63 0)
			(effects
				(font
					(size 1.27 1.27)
					(thickness 0.15)
				)
				(justify left bottom)
				(hide yes)
			)
		)
		(property "Footprint" "antmicro-footprints:C_0402_1005Metric"
			(at 247.65 214.63 0)
			(effects
				(font
					(size 1.27 1.27)
					(thickness 0.15)
				)
				(justify left bottom)
				(hide yes)
			)
		)
		(property "Datasheet" "https://www.murata.com/products/productdetail?partno=GRM155R61H104KE14%23"
			(at 250.19 214.63 0)
			(effects
				(font
					(size 1.27 1.27)
					(thickness 0.15)
				)
				(justify left bottom)
				(hide yes)
			)
		)
		(property "Description" "SMD Multilayer Ceramic Capacitor, 0.1 µF, 50 V, 0402 [1005 Metric], ± 10%, X5R, GRM Series"
			(at 234.95 234.95 0)
			(effects
				(font
					(size 1.27 1.27)
				)
				(hide yes)
			)
		)
		(property "Manufacturer" "Murata"
			(at 255.27 214.63 0)
			(effects
				(font
					(size 1.27 1.27)
					(thickness 0.15)
				)
				(justify left bottom)
				(hide yes)
			)
		)
		(property "MPN" "GRM155R61H104KE14D"
			(at 252.73 214.63 0)
			(effects
				(font
					(size 1.27 1.27)
					(thickness 0.15)
				)
				(justify left bottom)
				(hide yes)
			)
		)
		(property "Val" "100n"
			(at 232.41 233.6735 90)
			(effects
				(font
					(size 1.27 1.27)
					(thickness 0.15)
				)
				(justify left)
			)
		)
		(property "License" "Apache-2.0"
			(at 257.81 214.63 0)
			(effects
				(font
					(size 1.27 1.27)
					(thickness 0.15)
				)
				(justify left bottom)
				(hide yes)
			)
		)
		(property "Author" "Antmicro"
			(at 260.35 214.63 0)
			(effects
				(font
					(size 1.27 1.27)
					(thickness 0.15)
				)
				(justify left bottom)
				(hide yes)
			)
		)
		(property "Voltage" "50V"
			(at 262.89 214.63 0)
			(effects
				(font
					(size 1.27 1.27)
				)
				(justify left bottom)
				(hide yes)
			)
		)
		(property "Dielectric" "X5R"
			(at 265.43 214.63 0)
			(effects
				(font
					(size 1.27 1.27)
				)
				(justify left bottom)
				(hide yes)
			)
		)
		(pin "1"
		)
		(pin "2"
		)
		(instances
			(project "sdi-mipi-video-converter"
				(path ""
					(reference "C80")
					(unit 1)
				)
			)
		)
	)
	(symbol
		(lib_id "antmicropower:+3.3V")
		(at 134.62 251.46 0)
		(mirror y)
		(unit 1)
		(exclude_from_sim no)
		(in_bom yes)
		(on_board yes)
		(dnp no)
		(fields_autoplaced yes)
		(property "Reference" "#PWR0162"
			(at 134.62 255.27 0)
			(effects
				(font
					(size 1.27 1.27)
				)
				(hide yes)
			)
		)
		(property "Value" "+3V3"
			(at 132.08 250.1899 0)
			(effects
				(font
					(size 1.27 1.27)
				)
				(justify left)
			)
		)
		(property "Footprint" ""
			(at 134.62 251.46 0)
			(effects
				(font
					(size 1.27 1.27)
				)
				(hide yes)
			)
		)
		(property "Datasheet" ""
			(at 134.62 251.46 0)
			(effects
				(font
					(size 1.27 1.27)
				)
				(hide yes)
			)
		)
		(property "Description" ""
			(at 134.62 251.46 0)
			(effects
				(font
					(size 1.27 1.27)
				)
				(hide yes)
			)
		)
		(pin "1"
		)
		(instances
			(project "sdi-mipi-video-converter"
				(path ""
					(reference "#PWR0162")
					(unit 1)
				)
			)
		)
	)
	(symbol
		(lib_id "antmicroTestPoints:TP_0.75mm_SMD")
		(at 288.29 226.06 90)
		(unit 1)
		(exclude_from_sim no)
		(in_bom yes)
		(on_board yes)
		(dnp no)
		(fields_autoplaced yes)
		(property "Reference" "TP19"
			(at 288.29 219.71 90)
			(effects
				(font
					(size 1.27 1.27)
					(thickness 0.15)
				)
			)
		)
		(property "Value" "TP_0.75mm_SMD"
			(at 295.91 208.28 0)
			(effects
				(font
					(size 1.27 1.27)
					(thickness 0.15)
				)
				(justify left bottom)
				(hide yes)
			)
		)
		(property "Footprint" "antmicro-footprints:TP_SMD_0.75mm"
			(at 298.45 208.28 0)
			(effects
				(font
					(size 1.27 1.27)
					(thickness 0.15)
				)
				(justify left bottom)
				(hide yes)
			)
		)
		(property "Datasheet" ""
			(at 300.99 208.28 0)
			(effects
				(font
					(size 1.27 1.27)
					(thickness 0.15)
				)
				(justify left bottom)
				(hide yes)
			)
		)
		(property "Description" "SMT test point"
			(at 288.29 226.06 0)
			(effects
				(font
					(size 1.27 1.27)
				)
				(hide yes)
			)
		)
		(property "MPN" ""
			(at 303.53 208.28 0)
			(effects
				(font
					(size 1.27 1.27)
					(thickness 0.15)
				)
				(justify left bottom)
				(hide yes)
			)
		)
		(property "Manufacturer" ""
			(at 306.07 208.28 0)
			(effects
				(font
					(size 1.27 1.27)
					(thickness 0.15)
				)
				(justify left bottom)
				(hide yes)
			)
		)
		(property "Author" "Antmicro"
			(at 308.61 208.28 0)
			(effects
				(font
					(size 1.27 1.27)
					(thickness 0.15)
				)
				(justify left bottom)
				(hide yes)
			)
		)
		(property "License" "Apache-2.0"
			(at 311.15 208.28 0)
			(effects
				(font
					(size 1.27 1.27)
					(thickness 0.15)
				)
				(justify left bottom)
				(hide yes)
			)
		)
		(pin "1"
		)
		(instances
			(project "sdi-mipi-video-converter"
				(path ""
					(reference "TP19")
					(unit 1)
				)
			)
		)
	)
	(symbol
		(lib_id "antmicropower:GND")
		(at 147.32 269.24 0)
		(unit 1)
		(exclude_from_sim no)
		(in_bom yes)
		(on_board yes)
		(dnp no)
		(fields_autoplaced yes)
		(property "Reference" "#PWR0163"
			(at 156.21 271.78 0)
			(effects
				(font
					(size 1.27 1.27)
					(thickness 0.15)
				)
				(justify left bottom)
				(hide yes)
			)
		)
		(property "Value" "GND"
			(at 147.32 274.32 0)
			(effects
				(font
					(size 1.27 1.27)
					(thickness 0.15)
				)
			)
		)
		(property "Footprint" ""
			(at 156.21 276.86 0)
			(effects
				(font
					(size 1.27 1.27)
					(thickness 0.15)
				)
				(justify left bottom)
				(hide yes)
			)
		)
		(property "Datasheet" ""
			(at 156.21 281.94 0)
			(effects
				(font
					(size 1.27 1.27)
					(thickness 0.15)
				)
				(justify left bottom)
				(hide yes)
			)
		)
		(property "Description" ""
			(at 147.32 269.24 0)
			(effects
				(font
					(size 1.27 1.27)
				)
				(hide yes)
			)
		)
		(property "Author" "Antmicro"
			(at 156.21 276.86 0)
			(effects
				(font
					(size 1.27 1.27)
					(thickness 0.15)
				)
				(justify left bottom)
				(hide yes)
			)
		)
		(property "License" "Apache-2.0"
			(at 156.21 279.4 0)
			(effects
				(font
					(size 1.27 1.27)
					(thickness 0.15)
				)
				(justify left bottom)
				(hide yes)
			)
		)
		(pin "1"
		)
		(instances
			(project "sdi-mipi-video-converter"
				(path ""
					(reference "#PWR0163")
					(unit 1)
				)
			)
		)
	)
	(symbol
		(lib_id "antmicroLEDIndicationDiscrete:LED_R_0603_LTST-C190KRKT")
		(at 370.84 224.79 270)
		(mirror x)
		(unit 1)
		(exclude_from_sim no)
		(in_bom yes)
		(on_board yes)
		(dnp no)
		(fields_autoplaced yes)
		(property "Reference" "D6"
			(at 374.65 220.98 90)
			(effects
				(font
					(size 1.27 1.27)
					(thickness 0.15)
				)
				(justify left)
			)
		)
		(property "Value" "LED_R_0603_LTST-C190KRKT"
			(at 374.65 223.52 90)
			(effects
				(font
					(size 1.27 1.27)
					(thickness 0.15)
				)
				(justify left)
			)
		)
		(property "Footprint" "antmicro-footprints:LED_0603_1608Metric_R"
			(at 360.68 201.93 0)
			(effects
				(font
					(size 1.27 1.27)
					(thickness 0.15)
				)
				(justify left bottom)
				(hide yes)
			)
		)
		(property "Datasheet" "https://optoelectronics.liteon.com/upload/download/DS-22-99-0151/LTST-C190KRKT.pdf"
			(at 358.14 201.93 0)
			(effects
				(font
					(size 1.27 1.27)
					(thickness 0.15)
				)
				(justify left bottom)
				(hide yes)
			)
		)
		(property "Description" "LED, Red, SMD, 0603, 25 mA, 2 V, 631 nm"
			(at 370.84 224.79 0)
			(effects
				(font
					(size 1.27 1.27)
				)
				(hide yes)
			)
		)
		(property "MPN" "LTST-C190KRKT"
			(at 355.6 201.93 0)
			(effects
				(font
					(size 1.27 1.27)
					(thickness 0.15)
				)
				(justify left bottom)
				(hide yes)
			)
		)
		(property "Manufacturer" "Lite-On"
			(at 353.06 201.93 0)
			(effects
				(font
					(size 1.27 1.27)
					(thickness 0.15)
				)
				(justify left bottom)
				(hide yes)
			)
		)
		(property "Author" "Antmicro"
			(at 350.52 201.93 0)
			(effects
				(font
					(size 1.27 1.27)
					(thickness 0.15)
				)
				(justify left bottom)
				(hide yes)
			)
		)
		(property "License" "Apache-2.0"
			(at 347.98 201.93 0)
			(effects
				(font
					(size 1.27 1.27)
					(thickness 0.15)
				)
				(justify left bottom)
				(hide yes)
			)
		)
		(property "Color" "Red"
			(at 374.65 224.7899 90)
			(effects
				(font
					(size 1.27 1.27)
				)
				(justify left)
				(hide yes)
			)
		)
		(pin "1"
		)
		(pin "2"
		)
		(instances
			(project "sdi-mipi-video-converter"
				(path ""
					(reference "D6")
					(unit 1)
				)
			)
		)
	)
	(symbol
		(lib_id "antmicroTestPoints:TP_0.75mm_SMD")
		(at 379.73 229.87 0)
		(unit 1)
		(exclude_from_sim no)
		(in_bom yes)
		(on_board yes)
		(dnp no)
		(fields_autoplaced yes)
		(property "Reference" "TP22"
			(at 384.81 229.8699 0)
			(effects
				(font
					(size 1.27 1.27)
					(thickness 0.15)
				)
				(justify left)
			)
		)
		(property "Value" "TP_0.75mm_SMD"
			(at 397.51 237.49 0)
			(effects
				(font
					(size 1.27 1.27)
					(thickness 0.15)
				)
				(justify left bottom)
				(hide yes)
			)
		)
		(property "Footprint" "antmicro-footprints:TP_SMD_0.75mm"
			(at 397.51 240.03 0)
			(effects
				(font
					(size 1.27 1.27)
					(thickness 0.15)
				)
				(justify left bottom)
				(hide yes)
			)
		)
		(property "Datasheet" ""
			(at 397.51 242.57 0)
			(effects
				(font
					(size 1.27 1.27)
					(thickness 0.15)
				)
				(justify left bottom)
				(hide yes)
			)
		)
		(property "Description" "SMT test point"
			(at 379.73 229.87 0)
			(effects
				(font
					(size 1.27 1.27)
				)
				(hide yes)
			)
		)
		(property "MPN" ""
			(at 397.51 245.11 0)
			(effects
				(font
					(size 1.27 1.27)
					(thickness 0.15)
				)
				(justify left bottom)
				(hide yes)
			)
		)
		(property "Manufacturer" ""
			(at 397.51 247.65 0)
			(effects
				(font
					(size 1.27 1.27)
					(thickness 0.15)
				)
				(justify left bottom)
				(hide yes)
			)
		)
		(property "Author" "Antmicro"
			(at 397.51 250.19 0)
			(effects
				(font
					(size 1.27 1.27)
					(thickness 0.15)
				)
				(justify left bottom)
				(hide yes)
			)
		)
		(property "License" "Apache-2.0"
			(at 397.51 252.73 0)
			(effects
				(font
					(size 1.27 1.27)
					(thickness 0.15)
				)
				(justify left bottom)
				(hide yes)
			)
		)
		(pin "1"
		)
		(instances
			(project "sdi-mipi-video-converter"
				(path ""
					(reference "TP22")
					(unit 1)
				)
			)
		)
	)
	(symbol
		(lib_id "antmicropower:+3.3V")
		(at 251.46 123.19 0)
		(mirror y)
		(unit 1)
		(exclude_from_sim no)
		(in_bom yes)
		(on_board yes)
		(dnp no)
		(fields_autoplaced yes)
		(property "Reference" "#PWR0167"
			(at 251.46 127 0)
			(effects
				(font
					(size 1.27 1.27)
				)
				(hide yes)
			)
		)
		(property "Value" "+3V3"
			(at 251.46 118.11 0)
			(effects
				(font
					(size 1.27 1.27)
				)
			)
		)
		(property "Footprint" ""
			(at 251.46 123.19 0)
			(effects
				(font
					(size 1.27 1.27)
				)
				(hide yes)
			)
		)
		(property "Datasheet" ""
			(at 251.46 123.19 0)
			(effects
				(font
					(size 1.27 1.27)
				)
				(hide yes)
			)
		)
		(property "Description" ""
			(at 251.46 123.19 0)
			(effects
				(font
					(size 1.27 1.27)
				)
				(hide yes)
			)
		)
		(pin "1"
		)
		(instances
			(project "sdi-mipi-video-converter"
				(path ""
					(reference "#PWR0167")
					(unit 1)
				)
			)
		)
	)
	(symbol
		(lib_id "antmicropower:+3.3V")
		(at 240.03 123.19 0)
		(mirror y)
		(unit 1)
		(exclude_from_sim no)
		(in_bom yes)
		(on_board yes)
		(dnp no)
		(fields_autoplaced yes)
		(property "Reference" "#PWR0172"
			(at 240.03 127 0)
			(effects
				(font
					(size 1.27 1.27)
				)
				(hide yes)
			)
		)
		(property "Value" "+3V3"
			(at 237.49 121.9199 0)
			(effects
				(font
					(size 1.27 1.27)
				)
				(justify left)
			)
		)
		(property "Footprint" ""
			(at 240.03 123.19 0)
			(effects
				(font
					(size 1.27 1.27)
				)
				(hide yes)
			)
		)
		(property "Datasheet" ""
			(at 240.03 123.19 0)
			(effects
				(font
					(size 1.27 1.27)
				)
				(hide yes)
			)
		)
		(property "Description" ""
			(at 240.03 123.19 0)
			(effects
				(font
					(size 1.27 1.27)
				)
				(hide yes)
			)
		)
		(pin "1"
		)
		(instances
			(project "sdi-mipi-video-converter"
				(path ""
					(reference "#PWR0172")
					(unit 1)
				)
			)
		)
	)
	(symbol
		(lib_id "antmicroCapacitors0402:C_100n_0402")
		(at 142.24 267.97 270)
		(mirror x)
		(unit 1)
		(exclude_from_sim no)
		(in_bom yes)
		(on_board yes)
		(dnp no)
		(fields_autoplaced yes)
		(property "Reference" "C79"
			(at 139.7 264.1535 90)
			(effects
				(font
					(size 1.27 1.27)
					(thickness 0.15)
				)
				(justify right)
			)
		)
		(property "Value" "C_100n_0402"
			(at 132.08 247.65 0)
			(effects
				(font
					(size 1.27 1.27)
					(thickness 0.15)
				)
				(justify left bottom)
				(hide yes)
			)
		)
		(property "Footprint" "antmicro-footprints:C_0402_1005Metric"
			(at 129.54 247.65 0)
			(effects
				(font
					(size 1.27 1.27)
					(thickness 0.15)
				)
				(justify left bottom)
				(hide yes)
			)
		)
		(property "Datasheet" "https://www.murata.com/products/productdetail?partno=GRM155R61H104KE14%23"
			(at 127 247.65 0)
			(effects
				(font
					(size 1.27 1.27)
					(thickness 0.15)
				)
				(justify left bottom)
				(hide yes)
			)
		)
		(property "Description" "SMD Multilayer Ceramic Capacitor, 0.1 µF, 50 V, 0402 [1005 Metric], ± 10%, X5R, GRM Series"
			(at 142.24 267.97 0)
			(effects
				(font
					(size 1.27 1.27)
				)
				(hide yes)
			)
		)
		(property "Manufacturer" "Murata"
			(at 121.92 247.65 0)
			(effects
				(font
					(size 1.27 1.27)
					(thickness 0.15)
				)
				(justify left bottom)
				(hide yes)
			)
		)
		(property "MPN" "GRM155R61H104KE14D"
			(at 124.46 247.65 0)
			(effects
				(font
					(size 1.27 1.27)
					(thickness 0.15)
				)
				(justify left bottom)
				(hide yes)
			)
		)
		(property "Val" "100n"
			(at 139.7 266.6935 90)
			(effects
				(font
					(size 1.27 1.27)
					(thickness 0.15)
				)
				(justify right)
			)
		)
		(property "License" "Apache-2.0"
			(at 119.38 247.65 0)
			(effects
				(font
					(size 1.27 1.27)
					(thickness 0.15)
				)
				(justify left bottom)
				(hide yes)
			)
		)
		(property "Author" "Antmicro"
			(at 116.84 247.65 0)
			(effects
				(font
					(size 1.27 1.27)
					(thickness 0.15)
				)
				(justify left bottom)
				(hide yes)
			)
		)
		(property "Voltage" "50V"
			(at 114.3 247.65 0)
			(effects
				(font
					(size 1.27 1.27)
				)
				(justify left bottom)
				(hide yes)
			)
		)
		(property "Dielectric" "X5R"
			(at 111.76 247.65 0)
			(effects
				(font
					(size 1.27 1.27)
				)
				(justify left bottom)
				(hide yes)
			)
		)
		(pin "1"
		)
		(pin "2"
		)
		(instances
			(project "sdi-mipi-video-converter"
				(path ""
					(reference "C79")
					(unit 1)
				)
			)
		)
	)
	(symbol
		(lib_id "antmicroResistors0402:R_0R_0402")
		(at 370.84 110.49 0)
		(unit 1)
		(exclude_from_sim no)
		(in_bom yes)
		(on_board yes)
		(dnp no)
		(property "Reference" "R92"
			(at 368.935 109.22 0)
			(effects
				(font
					(size 1.27 1.27)
					(thickness 0.15)
				)
			)
		)
		(property "Value" "R_0R_0402"
			(at 391.16 123.19 0)
			(effects
				(font
					(size 1.27 1.27)
					(thickness 0.15)
				)
				(justify left bottom)
				(hide yes)
			)
		)
		(property "Footprint" "antmicro-footprints:R_0402_1005Metric"
			(at 391.16 125.73 0)
			(effects
				(font
					(size 1.27 1.27)
					(thickness 0.15)
				)
				(justify left bottom)
				(hide yes)
			)
		)
		(property "Datasheet" "https://industrial.panasonic.com/cdbs/www-data/pdf/RDA0000/AOA0000C301.pdf"
			(at 391.16 128.27 0)
			(effects
				(font
					(size 1.27 1.27)
					(thickness 0.15)
				)
				(justify left bottom)
				(hide yes)
			)
		)
		(property "Description" "SMD Chip Resistor, Jumper, 0 ohm, 100 mW, 0402 [1005 Metric], Thick Film, General Purpose"
			(at 370.84 110.49 0)
			(effects
				(font
					(size 1.27 1.27)
				)
				(hide yes)
			)
		)
		(property "Manufacturer" "Panasonic"
			(at 391.16 133.35 0)
			(effects
				(font
					(size 1.27 1.27)
					(thickness 0.15)
				)
				(justify left bottom)
				(hide yes)
			)
		)
		(property "MPN" "ERJ2GE0R00X"
			(at 391.16 130.81 0)
			(effects
				(font
					(size 1.27 1.27)
					(thickness 0.15)
				)
				(justify left bottom)
				(hide yes)
			)
		)
		(property "Val" "0R"
			(at 377.19 109.22 0)
			(effects
				(font
					(size 1.27 1.27)
					(thickness 0.15)
				)
			)
		)
		(property "License" "Apache-2.0"
			(at 391.16 135.89 0)
			(effects
				(font
					(size 1.27 1.27)
					(thickness 0.15)
				)
				(justify left bottom)
				(hide yes)
			)
		)
		(property "Author" "Antmicro"
			(at 391.16 138.43 0)
			(effects
				(font
					(size 1.27 1.27)
					(thickness 0.15)
				)
				(justify left bottom)
				(hide yes)
			)
		)
		(property "Tolerance" "~"
			(at 391.16 120.65 0)
			(effects
				(font
					(size 1.27 1.27)
				)
				(justify left bottom)
				(hide yes)
			)
		)
		(property "Current" "1A"
			(at 391.16 140.97 0)
			(effects
				(font
					(size 1.27 1.27)
					(thickness 0.15)
				)
				(justify left bottom)
				(hide yes)
			)
		)
		(pin "1"
		)
		(pin "2"
		)
		(instances
			(project "sdi-mipi-video-converter"
				(path ""
					(reference "R92")
					(unit 1)
				)
			)
		)
	)
)
